FILE_TYPE = MACRO_DRAWING;
SET COLOR_WIRE YELLOW;
SET COLOR_PROP MONO;
SET COLOR_DOT WHITE;
SET COLOR_ARC YELLOW;
SET COLOR_BODY GREEN;
SET COLOR_NOTE MONO;
SET PROP_DISPLAY VALUE;
SET PAGE_NUMBER P190;
FORCEADD RES..1
(-4150 5200);
FORCEPROP 1 LASTPIN (-4050 5200) $PN 2
J 0
(-4088 5212);
DISPLAY 0.617021 (-4088 5212);
PAINT ORANGE (-4088 5212);
FORCEPROP 1 LASTPIN (-4250 5200) $PN 1
J 0
(-4238 5212);
DISPLAY 0.617021 (-4238 5212);
PAINT ORANGE (-4238 5212);
FORCEPROP 1 LAST WATTAGE 1/16W
J 2
(-4175 5050);
DISPLAY 0.617021 (-4175 5050);
PAINT SKYBLUE (-4175 5050);
FORCEPROP 1 LAST MATERIAL CHIP
J 0
(-4150 5050);
DISPLAY 0.617021 (-4150 5050);
PAINT SKYBLUE (-4150 5050);
FORCEPROP 1 LAST PACK_TYPE 0402
J 0
(-4075 5100);
DISPLAY 0.617021 (-4075 5100);
PAINT SKYBLUE (-4075 5100);
FORCEPROP 1 LAST TOLERANCE 5%
J 0
(-4200 5100);
DISPLAY 0.617021 (-4200 5100);
PAINT SKYBLUE (-4200 5100);
FORCEPROP 1 LAST VALUE 0.0
J 2
(-4250 5100);
DISPLAY 0.617021 (-4250 5100);
PAINT SKYBLUE (-4250 5100);
FORCEPROP 1 LAST PART_NUMBER G21497-005
J 0
(-4300 5150);
DISPLAY 0.617021 (-4300 5150);
PAINT BLUE (-4300 5150);
FORCEPROP 1 LAST LOCATION R3P34
J 0
(-4375 5225);
DISPLAY 0.617021 (-4375 5225);
PAINT AQUA (-4375 5225);
FORCEPROP 2 LAST SEC_TYPE 0402
J 0
(-4200 5400);
DISPLAY 1.021277 (-4200 5400);
PAINT ORANGE (-4200 5400);
DISPLAY INVISIBLE (-4200 5400);
FORCEPROP 2 LAST CDS_LIB mstr_discrete
J 0
(-4150 5200);
PAINT ORANGE (-4150 5200);
DISPLAY INVISIBLE (-4150 5200);
FORCEPROP 0 LAST BOM_COST CPLD
J 0
(-4375 5325);
DISPLAY 1.021277 (-4375 5325);
PAINT ORANGE (-4375 5325);
DISPLAY INVISIBLE (-4375 5325);
FORCEPROP 2 LAST SEC 1
J 0
(-4200 5400);
DISPLAY 0.680851 (-4200 5400);
PAINT MONO (-4200 5400);
DISPLAY INVISIBLE (-4200 5400);
FORCEPROP 2 LAST CDS_LOCATION R3P34
J 0
(-4375 5225);
DISPLAY 0.617021 (-4375 5225);
PAINT AQUA (-4375 5225);
DISPLAY INVISIBLE (-4375 5225);
FORCEPROP 1 LAST PATH I116
J 0
(-4200 5350);
DISPLAY 0.978723 (-4200 5350);
PAINT WHITE (-4200 5350);
DISPLAY INVISIBLE (-4200 5350);
FORCEPROP 2 LAST ROOM CPLD
J 0
(-4200 5300);
DISPLAY 1.361702 (-4200 5300);
PAINT ORANGE (-4200 5300);
DISPLAY INVISIBLE (-4200 5300);
FORCEADD RES..1
(-4150 5000);
FORCEPROP 1 LASTPIN (-4050 5000) $PN 2
J 0
(-4088 5012);
DISPLAY 0.617021 (-4088 5012);
PAINT ORANGE (-4088 5012);
FORCEPROP 1 LASTPIN (-4250 5000) $PN 1
J 0
(-4238 5012);
DISPLAY 0.617021 (-4238 5012);
PAINT ORANGE (-4238 5012);
FORCEPROP 1 LAST WATTAGE 1/16W
J 2
(-4400 4900);
DISPLAY 0.617021 (-4400 4900);
PAINT SKYBLUE (-4400 4900);
FORCEPROP 1 LAST PACK_TYPE 0402
J 0
(-4075 4900);
DISPLAY 0.617021 (-4075 4900);
PAINT SKYBLUE (-4075 4900);
FORCEPROP 1 LAST TOLERANCE 5%
J 0
(-4200 4900);
DISPLAY 0.617021 (-4200 4900);
PAINT SKYBLUE (-4200 4900);
FORCEPROP 1 LAST VALUE 0.0
J 2
(-4250 4900);
DISPLAY 0.617021 (-4250 4900);
PAINT SKYBLUE (-4250 4900);
FORCEPROP 1 LAST PART_NUMBER G21497-005
J 0
(-4300 4950);
DISPLAY 0.617021 (-4300 4950);
PAINT BLUE (-4300 4950);
FORCEPROP 1 LAST LOCATION R3P35
J 0
(-4375 5000);
DISPLAY 0.617021 (-4375 5000);
PAINT AQUA (-4375 5000);
FORCEPROP 1 LAST MATERIAL CHIP
J 0
(-3950 4900);
DISPLAY 0.617021 (-3950 4900);
PAINT SKYBLUE (-3950 4900);
FORCEPROP 2 LAST SEC_TYPE 0402
J 0
(-4200 5200);
DISPLAY 1.021277 (-4200 5200);
PAINT ORANGE (-4200 5200);
DISPLAY INVISIBLE (-4200 5200);
FORCEPROP 0 LAST BOM_COST CPLD
J 0
(-4375 5100);
DISPLAY 1.021277 (-4375 5100);
PAINT ORANGE (-4375 5100);
DISPLAY INVISIBLE (-4375 5100);
FORCEPROP 2 LAST CDS_LIB mstr_discrete
J 0
(-4150 5000);
PAINT ORANGE (-4150 5000);
DISPLAY INVISIBLE (-4150 5000);
FORCEPROP 2 LAST SEC 1
J 0
(-4200 5200);
DISPLAY 0.680851 (-4200 5200);
PAINT MONO (-4200 5200);
DISPLAY INVISIBLE (-4200 5200);
FORCEPROP 2 LAST CDS_LOCATION R3P35
J 0
(-4375 5000);
DISPLAY 0.617021 (-4375 5000);
PAINT AQUA (-4375 5000);
DISPLAY INVISIBLE (-4375 5000);
FORCEPROP 1 LAST PATH I117
J 0
(-4200 5150);
DISPLAY 0.978723 (-4200 5150);
PAINT WHITE (-4200 5150);
DISPLAY INVISIBLE (-4200 5150);
FORCEPROP 2 LAST ROOM CPLD
J 0
(-4200 5100);
DISPLAY 1.361702 (-4200 5100);
PAINT ORANGE (-4200 5100);
DISPLAY INVISIBLE (-4200 5100);
FORCEADD OFFPAGE..1
(-4925 5000);
FORCEPROP 2 LAST $XR0 190 
J 0
(-5177 5000);
DISPLAY 0.638298 (-5177 5000);
PAINT MONO (-5177 5000);
FORCEPROP 2 LAST PATH I118
J 0
(-4875 5075);
DISPLAY 1.021277 (-4875 5075);
PAINT ORANGE (-4875 5075);
DISPLAY INVISIBLE (-4875 5075);
FORCEPROP 1 LAST COMMENT_BODY TRUE
J 0
(-4800 4900);
DISPLAY 1.893617 (-4800 4900);
PAINT PEACH (-4800 4900);
DISPLAY INVISIBLE (-4800 4900);
FORCEPROP 1 LAST OFFPAGE TRUE
J 0
(-4600 4875);
PAINT GREEN (-4600 4875);
DISPLAY INVISIBLE (-4600 4875);
FORCEPROP 2 LAST CDS_LIB mstr_standard
J 0
(-4925 5000);
PAINT ORANGE (-4925 5000);
DISPLAY INVISIBLE (-4925 5000);
FORCEPROP 2 LAST BOM_COST SB_RESET
J 0
(-5175 5050);
DISPLAY 1.617021 (-5175 5050);
PAINT WHITE (-5175 5050);
DISPLAY INVISIBLE (-5175 5050);
FORCEPROP 2 LAST ROOM PLD
J 0
(-5175 5050);
DISPLAY 1.617021 (-5175 5050);
PAINT WHITE (-5175 5050);
DISPLAY INVISIBLE (-5175 5050);
FORCEADD OFFPAGE..1
(-4925 5200);
FORCEPROP 2 LAST $XR0 190 
J 0
(-5177 5200);
DISPLAY 0.638298 (-5177 5200);
PAINT MONO (-5177 5200);
FORCEPROP 2 LAST PATH I119
J 0
(-4875 5275);
DISPLAY 1.021277 (-4875 5275);
PAINT ORANGE (-4875 5275);
DISPLAY INVISIBLE (-4875 5275);
FORCEPROP 1 LAST COMMENT_BODY TRUE
J 0
(-4800 5100);
DISPLAY 1.893617 (-4800 5100);
PAINT PEACH (-4800 5100);
DISPLAY INVISIBLE (-4800 5100);
FORCEPROP 1 LAST OFFPAGE TRUE
J 0
(-4600 5075);
PAINT GREEN (-4600 5075);
DISPLAY INVISIBLE (-4600 5075);
FORCEPROP 2 LAST CDS_LIB mstr_standard
J 0
(-4925 5200);
PAINT ORANGE (-4925 5200);
DISPLAY INVISIBLE (-4925 5200);
FORCEPROP 2 LAST ROOM PLD
J 0
(-5175 5250);
DISPLAY 1.617021 (-5175 5250);
PAINT WHITE (-5175 5250);
DISPLAY INVISIBLE (-5175 5250);
FORCEPROP 2 LAST BOM_COST SB_RESET
J 0
(-5175 5250);
DISPLAY 1.617021 (-5175 5250);
PAINT WHITE (-5175 5250);
DISPLAY INVISIBLE (-5175 5250);
FORCEADD OFFPAGE..2
(-3175 5200);
FORCEPROP 2 LAST $XR0 96 
J 0
(-2986 5200);
DISPLAY 0.638298 (-2986 5200);
PAINT MONO (-2986 5200);
FORCEPROP 2 LAST PATH I120
J 0
(-3125 5275);
DISPLAY 1.021277 (-3125 5275);
PAINT ORANGE (-3125 5275);
DISPLAY INVISIBLE (-3125 5275);
FORCEPROP 1 LAST COMMENT_BODY TRUE
J 0
(-3220 5105);
DISPLAY 0.872340 (-3220 5105);
PAINT GREEN (-3220 5105);
DISPLAY INVISIBLE (-3220 5105);
FORCEPROP 1 LAST OFFPAGE TRUE
J 0
(-2850 5075);
DISPLAY 0.872340 (-2850 5075);
PAINT GREEN (-2850 5075);
DISPLAY INVISIBLE (-2850 5075);
FORCEPROP 2 LAST BOM_COST SB_RESET
J 0
(-3425 5250);
DISPLAY 1.617021 (-3425 5250);
PAINT WHITE (-3425 5250);
DISPLAY INVISIBLE (-3425 5250);
FORCEPROP 2 LAST ROOM PLD
J 0
(-3425 5250);
DISPLAY 1.617021 (-3425 5250);
PAINT WHITE (-3425 5250);
DISPLAY INVISIBLE (-3425 5250);
FORCEPROP 2 LAST CDS_LIB mstr_standard
J 0
(-3175 5200);
PAINT ORANGE (-3175 5200);
DISPLAY INVISIBLE (-3175 5200);
FORCEADD OFFPAGE..2
(-3175 5000);
FORCEPROP 2 LAST $XR0 96 
J 0
(-2986 5000);
DISPLAY 0.638298 (-2986 5000);
PAINT MONO (-2986 5000);
FORCEPROP 2 LAST PATH I121
J 0
(-3000 5075);
DISPLAY 1.021277 (-3000 5075);
PAINT ORANGE (-3000 5075);
DISPLAY INVISIBLE (-3000 5075);
FORCEPROP 1 LAST COMMENT_BODY TRUE
J 0
(-3220 4905);
DISPLAY 0.872340 (-3220 4905);
PAINT GREEN (-3220 4905);
DISPLAY INVISIBLE (-3220 4905);
FORCEPROP 1 LAST OFFPAGE TRUE
J 0
(-2850 4875);
DISPLAY 0.872340 (-2850 4875);
PAINT GREEN (-2850 4875);
DISPLAY INVISIBLE (-2850 4875);
FORCEPROP 2 LAST ROOM PLD
J 0
(-3425 5050);
DISPLAY 1.617021 (-3425 5050);
PAINT WHITE (-3425 5050);
DISPLAY INVISIBLE (-3425 5050);
FORCEPROP 2 LAST BOM_COST SB_RESET
J 0
(-3425 5050);
DISPLAY 1.617021 (-3425 5050);
PAINT WHITE (-3425 5050);
DISPLAY INVISIBLE (-3425 5050);
FORCEPROP 2 LAST CDS_LIB mstr_standard
J 0
(-3175 5000);
PAINT ORANGE (-3175 5000);
DISPLAY INVISIBLE (-3175 5000);
FORCEADD OFFPAGE..4
(550 4500);
FORCEPROP 2 LAST $XR0 119 
J 0
(736 4500);
DISPLAY 0.638298 (736 4500);
PAINT MONO (736 4500);
FORCEPROP 2 LAST PATH I122
J 0
(750 4550);
DISPLAY 1.021277 (750 4550);
PAINT ORANGE (750 4550);
DISPLAY INVISIBLE (750 4550);
FORCEPROP 1 LAST COMMENT_BODY TRUE
J 0
(525 4400);
DISPLAY 1.170213 (525 4400);
PAINT GREEN (525 4400);
DISPLAY INVISIBLE (525 4400);
FORCEPROP 1 LAST OFFPAGE TRUE
J 0
(875 4375);
DISPLAY 1.170213 (875 4375);
PAINT GREEN (875 4375);
DISPLAY INVISIBLE (875 4375);
FORCEPROP 2 LAST CDS_LIB mstr_standard
J 0
(550 4500);
PAINT ORANGE (550 4500);
DISPLAY INVISIBLE (550 4500);
FORCEADD OFFPAGE..2
(550 4100);
FORCEPROP 2 LAST $XR0 185 
J 0
(739 4100);
DISPLAY 0.638298 (739 4100);
PAINT MONO (739 4100);
FORCEPROP 2 LAST PATH I134
J 0
(750 4150);
DISPLAY 1.021277 (750 4150);
PAINT ORANGE (750 4150);
DISPLAY INVISIBLE (750 4150);
FORCEPROP 1 LAST COMMENT_BODY TRUE
J 0
(505 4005);
DISPLAY 1.170213 (505 4005);
PAINT GREEN (505 4005);
DISPLAY INVISIBLE (505 4005);
FORCEPROP 1 LAST OFFPAGE TRUE
J 0
(875 3975);
DISPLAY 1.170213 (875 3975);
PAINT GREEN (875 3975);
DISPLAY INVISIBLE (875 3975);
FORCEPROP 2 LAST CDS_LIB mstr_standard
J 0
(550 4100);
PAINT ORANGE (550 4100);
DISPLAY INVISIBLE (550 4100);
FORCEADD OFFPAGE..4
(550 3650);
FORCEPROP 2 LAST $XR1 230 
J 0
(856 3650);
DISPLAY 0.638298 (856 3650);
PAINT MONO (856 3650);
FORCEPROP 2 LAST $XR0 229 
J 0
(736 3650);
DISPLAY 0.638298 (736 3650);
PAINT MONO (736 3650);
FORCEPROP 2 LAST PATH I139
J 0
(1050 3700);
DISPLAY 1.021277 (1050 3700);
PAINT ORANGE (1050 3700);
DISPLAY INVISIBLE (1050 3700);
FORCEPROP 1 LAST COMMENT_BODY TRUE
J 0
(525 3550);
DISPLAY 1.170213 (525 3550);
PAINT GREEN (525 3550);
DISPLAY INVISIBLE (525 3550);
FORCEPROP 1 LAST OFFPAGE TRUE
J 0
(875 3525);
DISPLAY 1.170213 (875 3525);
PAINT GREEN (875 3525);
DISPLAY INVISIBLE (875 3525);
FORCEPROP 2 LAST CDS_LIB mstr_standard
J 2
(550 3650);
PAINT ORANGE (550 3650);
DISPLAY INVISIBLE (550 3650);
FORCEADD OFFPAGE..4
(550 3150);
FORCEPROP 2 LAST $XR0 235 
J 0
(736 3150);
DISPLAY 0.638298 (736 3150);
PAINT MONO (736 3150);
FORCEPROP 2 LAST PATH I146
J 0
(1350 3200);
DISPLAY 1.021277 (1350 3200);
PAINT ORANGE (1350 3200);
DISPLAY INVISIBLE (1350 3200);
FORCEPROP 1 LAST COMMENT_BODY TRUE
J 0
(525 3050);
DISPLAY 1.170213 (525 3050);
PAINT GREEN (525 3050);
DISPLAY INVISIBLE (525 3050);
FORCEPROP 1 LAST OFFPAGE TRUE
J 0
(875 3025);
DISPLAY 1.170213 (875 3025);
PAINT GREEN (875 3025);
DISPLAY INVISIBLE (875 3025);
FORCEPROP 2 LAST CDS_LIB mstr_standard
J 2
(550 3150);
PAINT ORANGE (550 3150);
DISPLAY INVISIBLE (550 3150);
FORCEADD OFFPAGE..2
(550 2350);
FORCEPROP 2 LAST $XR1 63 
J 0
(859 2350);
DISPLAY 0.638298 (859 2350);
PAINT MONO (859 2350);
FORCEPROP 2 LAST $XR0 192 
J 0
(739 2350);
DISPLAY 0.638298 (739 2350);
PAINT MONO (739 2350);
FORCEPROP 2 LAST PATH I157
J 0
(750 2400);
DISPLAY 1.021277 (750 2400);
PAINT ORANGE (750 2400);
DISPLAY INVISIBLE (750 2400);
FORCEPROP 1 LAST COMMENT_BODY TRUE
J 0
(505 2255);
DISPLAY 1.170213 (505 2255);
PAINT GREEN (505 2255);
DISPLAY INVISIBLE (505 2255);
FORCEPROP 1 LAST OFFPAGE TRUE
J 0
(875 2225);
DISPLAY 1.170213 (875 2225);
PAINT GREEN (875 2225);
DISPLAY INVISIBLE (875 2225);
FORCEPROP 2 LAST CDS_LIB mstr_standard
J 0
(550 2350);
PAINT ORANGE (550 2350);
DISPLAY INVISIBLE (550 2350);
FORCEADD OFFPAGE..2
(550 2250);
FORCEPROP 2 LAST $XR0 190 
J 0
(739 2250);
DISPLAY 0.638298 (739 2250);
PAINT MONO (739 2250);
FORCEPROP 2 LAST PATH I159
J 0
(750 2300);
DISPLAY 1.021277 (750 2300);
PAINT ORANGE (750 2300);
DISPLAY INVISIBLE (750 2300);
FORCEPROP 1 LAST COMMENT_BODY TRUE
J 0
(505 2155);
DISPLAY 1.170213 (505 2155);
PAINT GREEN (505 2155);
DISPLAY INVISIBLE (505 2155);
FORCEPROP 1 LAST OFFPAGE TRUE
J 0
(875 2125);
DISPLAY 1.170213 (875 2125);
PAINT GREEN (875 2125);
DISPLAY INVISIBLE (875 2125);
FORCEPROP 2 LAST CDS_LIB mstr_standard
J 0
(550 2250);
PAINT ORANGE (550 2250);
DISPLAY INVISIBLE (550 2250);
FORCEADD OFFPAGE..4
(550 2100);
FORCEPROP 2 LAST $XR0 55 
J 0
(736 2100);
DISPLAY 0.638298 (736 2100);
PAINT MONO (736 2100);
FORCEPROP 2 LAST PATH I161
J 0
(750 2150);
DISPLAY 1.021277 (750 2150);
PAINT ORANGE (750 2150);
DISPLAY INVISIBLE (750 2150);
FORCEPROP 1 LAST COMMENT_BODY TRUE
J 0
(525 2000);
DISPLAY 1.170213 (525 2000);
PAINT GREEN (525 2000);
DISPLAY INVISIBLE (525 2000);
FORCEPROP 1 LAST OFFPAGE TRUE
J 0
(875 1975);
DISPLAY 1.170213 (875 1975);
PAINT GREEN (875 1975);
DISPLAY INVISIBLE (875 1975);
FORCEPROP 2 LAST CDS_LIB mstr_standard
J 0
(550 2100);
PAINT ORANGE (550 2100);
DISPLAY INVISIBLE (550 2100);
FORCEADD OFFPAGE..2
(550 2000);
FORCEPROP 2 LAST $XR0 96 
J 0
(739 2000);
DISPLAY 0.638298 (739 2000);
PAINT MONO (739 2000);
FORCEPROP 2 LAST PATH I162
J 0
(750 2050);
DISPLAY 1.021277 (750 2050);
PAINT ORANGE (750 2050);
DISPLAY INVISIBLE (750 2050);
FORCEPROP 1 LAST COMMENT_BODY TRUE
J 0
(505 1905);
DISPLAY 1.170213 (505 1905);
PAINT GREEN (505 1905);
DISPLAY INVISIBLE (505 1905);
FORCEPROP 1 LAST OFFPAGE TRUE
J 0
(875 1875);
DISPLAY 1.170213 (875 1875);
PAINT GREEN (875 1875);
DISPLAY INVISIBLE (875 1875);
FORCEPROP 2 LAST CDS_LIB mstr_standard
J 0
(550 2000);
PAINT ORANGE (550 2000);
DISPLAY INVISIBLE (550 2000);
FORCEADD OFFPAGE..2
(550 1850);
FORCEPROP 2 LAST $XR0 102 
J 0
(739 1850);
DISPLAY 0.638298 (739 1850);
PAINT MONO (739 1850);
FORCEPROP 2 LAST PATH I165
J 0
(1200 1900);
DISPLAY 1.021277 (1200 1900);
PAINT ORANGE (1200 1900);
DISPLAY INVISIBLE (1200 1900);
FORCEPROP 1 LAST COMMENT_BODY TRUE
J 0
(505 1755);
DISPLAY 1.170213 (505 1755);
PAINT GREEN (505 1755);
DISPLAY INVISIBLE (505 1755);
FORCEPROP 1 LAST OFFPAGE TRUE
J 0
(875 1725);
DISPLAY 1.170213 (875 1725);
PAINT GREEN (875 1725);
DISPLAY INVISIBLE (875 1725);
FORCEPROP 2 LAST CDS_LIB mstr_standard
J 2
(550 1850);
PAINT ORANGE (550 1850);
DISPLAY INVISIBLE (550 1850);
FORCEADD OFFPAGE..4
(550 1700);
FORCEPROP 2 LAST $XR2 144 
J 0
(946 1700);
DISPLAY 0.638298 (946 1700);
PAINT MONO (946 1700);
FORCEPROP 2 LAST $XR1 118 
J 0
(826 1700);
DISPLAY 0.638298 (826 1700);
PAINT MONO (826 1700);
FORCEPROP 2 LAST $XR0 21 
J 0
(736 1700);
DISPLAY 0.638298 (736 1700);
PAINT MONO (736 1700);
FORCEPROP 2 LAST PATH I167
J 0
(1175 1750);
DISPLAY 1.021277 (1175 1750);
PAINT ORANGE (1175 1750);
DISPLAY INVISIBLE (1175 1750);
FORCEPROP 1 LAST COMMENT_BODY TRUE
J 0
(525 1600);
DISPLAY 1.170213 (525 1600);
PAINT GREEN (525 1600);
DISPLAY INVISIBLE (525 1600);
FORCEPROP 1 LAST OFFPAGE TRUE
J 0
(875 1575);
DISPLAY 1.170213 (875 1575);
PAINT GREEN (875 1575);
DISPLAY INVISIBLE (875 1575);
FORCEPROP 2 LAST CDS_LIB mstr_standard
J 0
(550 1700);
PAINT ORANGE (550 1700);
DISPLAY INVISIBLE (550 1700);
FORCEADD OFFPAGE..4
(550 1600);
FORCEPROP 2 LAST $XR1 113 
J 0
(826 1600);
DISPLAY 0.638298 (826 1600);
PAINT MONO (826 1600);
FORCEPROP 2 LAST $XR0 55 
J 0
(736 1600);
DISPLAY 0.638298 (736 1600);
PAINT MONO (736 1600);
FORCEPROP 2 LAST PATH I168
J 0
(750 1650);
DISPLAY 1.021277 (750 1650);
PAINT ORANGE (750 1650);
DISPLAY INVISIBLE (750 1650);
FORCEPROP 1 LAST COMMENT_BODY TRUE
J 0
(525 1500);
DISPLAY 1.170213 (525 1500);
PAINT GREEN (525 1500);
DISPLAY INVISIBLE (525 1500);
FORCEPROP 1 LAST OFFPAGE TRUE
J 0
(875 1475);
DISPLAY 1.170213 (875 1475);
PAINT GREEN (875 1475);
DISPLAY INVISIBLE (875 1475);
FORCEPROP 2 LAST CDS_LIB mstr_standard
J 0
(550 1600);
PAINT ORANGE (550 1600);
DISPLAY INVISIBLE (550 1600);
FORCEADD OFFPAGE..4
(550 1300);
FORCEPROP 2 LAST $XR1 144 
J 0
(826 1300);
DISPLAY 0.638298 (826 1300);
PAINT MONO (826 1300);
FORCEPROP 2 LAST $XR0 92 
J 0
(736 1300);
DISPLAY 0.638298 (736 1300);
PAINT MONO (736 1300);
FORCEPROP 2 LAST PATH I171
J 0
(750 1350);
DISPLAY 1.021277 (750 1350);
PAINT ORANGE (750 1350);
DISPLAY INVISIBLE (750 1350);
FORCEPROP 1 LAST COMMENT_BODY TRUE
J 0
(525 1200);
DISPLAY 1.170213 (525 1200);
PAINT GREEN (525 1200);
DISPLAY INVISIBLE (525 1200);
FORCEPROP 1 LAST OFFPAGE TRUE
J 0
(875 1175);
DISPLAY 1.170213 (875 1175);
PAINT GREEN (875 1175);
DISPLAY INVISIBLE (875 1175);
FORCEPROP 2 LAST CDS_LIB mstr_standard
J 0
(550 1300);
PAINT ORANGE (550 1300);
DISPLAY INVISIBLE (550 1300);
FORCEADD LCMXO2_A..4
(-1950 2950);
FORCEPROP 2 LASTPIN (-2550 2950) $PN J1
J 2
(-2560 2960);
DISPLAY 0.617021 (-2560 2960);
PAINT ORANGE (-2560 2960);
FORCEPROP 2 LASTPIN (-1350 2350) $PN P10
J 0
(-1340 2360);
DISPLAY 0.617021 (-1340 2360);
PAINT ORANGE (-1340 2360);
FORCEPROP 2 LASTPIN (-1350 2450) $PN L10
J 0
(-1340 2460);
DISPLAY 0.617021 (-1340 2460);
PAINT ORANGE (-1340 2460);
FORCEPROP 2 LASTPIN (-1350 2500) $PN M9
J 0
(-1340 2510);
DISPLAY 0.617021 (-1340 2510);
PAINT ORANGE (-1340 2510);
FORCEPROP 2 LASTPIN (-2550 3400) $PN H6
J 2
(-2560 3410);
DISPLAY 0.617021 (-2560 3410);
PAINT ORANGE (-2560 3410);
FORCEPROP 2 LASTPIN (-1350 4600) $PN P4
J 0
(-1340 4610);
DISPLAY 0.617021 (-1340 4610);
PAINT ORANGE (-1340 4610);
FORCEPROP 2 LASTPIN (-1350 4550) $PN T4
J 0
(-1340 4560);
DISPLAY 0.617021 (-1340 4560);
PAINT ORANGE (-1340 4560);
FORCEPROP 2 LASTPIN (-1350 4500) $PN T2
J 0
(-1340 4510);
DISPLAY 0.617021 (-1340 4510);
PAINT ORANGE (-1340 4510);
FORCEPROP 2 LASTPIN (-1350 4450) $PN R3
J 0
(-1340 4460);
DISPLAY 0.617021 (-1340 4460);
PAINT ORANGE (-1340 4460);
FORCEPROP 2 LASTPIN (-1350 4350) $PN R5
J 0
(-1340 4360);
DISPLAY 0.617021 (-1340 4360);
PAINT ORANGE (-1340 4360);
FORCEPROP 2 LASTPIN (-1350 4300) $PN P5
J 0
(-1340 4310);
DISPLAY 0.617021 (-1340 4310);
PAINT ORANGE (-1340 4310);
FORCEPROP 2 LASTPIN (-1350 4150) $PN T5
J 0
(-1340 4160);
DISPLAY 0.617021 (-1340 4160);
PAINT ORANGE (-1340 4160);
FORCEPROP 2 LASTPIN (-1350 4100) $PN R6
J 0
(-1340 4110);
DISPLAY 0.617021 (-1340 4110);
PAINT ORANGE (-1340 4110);
FORCEPROP 2 LASTPIN (-1350 4050) $PN T3
J 0
(-1340 4060);
DISPLAY 0.617021 (-1340 4060);
PAINT ORANGE (-1340 4060);
FORCEPROP 2 LASTPIN (-1350 4000) $PN R4
J 0
(-1340 4010);
DISPLAY 0.617021 (-1340 4010);
PAINT ORANGE (-1340 4010);
FORCEPROP 2 LASTPIN (-1350 3900) $PN P6
J 0
(-1340 3910);
DISPLAY 0.617021 (-1340 3910);
PAINT ORANGE (-1340 3910);
FORCEPROP 2 LASTPIN (-1350 3850) $PN T6
J 0
(-1340 3860);
DISPLAY 0.617021 (-1340 3860);
PAINT ORANGE (-1340 3860);
FORCEPROP 2 LASTPIN (-1350 3800) $PN N6
J 0
(-1340 3810);
DISPLAY 0.617021 (-1340 3810);
PAINT ORANGE (-1340 3810);
FORCEPROP 2 LASTPIN (-1350 3750) $PN L7
J 0
(-1340 3760);
DISPLAY 0.617021 (-1340 3760);
PAINT ORANGE (-1340 3760);
FORCEPROP 2 LASTPIN (-1350 3650) $PN R7
J 0
(-1340 3660);
DISPLAY 0.617021 (-1340 3660);
PAINT ORANGE (-1340 3660);
FORCEPROP 2 LASTPIN (-1350 3600) $PN P7
J 0
(-1340 3610);
DISPLAY 0.617021 (-1340 3610);
PAINT ORANGE (-1340 3610);
FORCEPROP 2 LASTPIN (-1350 3550) $PN M7
J 0
(-1340 3560);
DISPLAY 0.617021 (-1340 3560);
PAINT ORANGE (-1340 3560);
FORCEPROP 2 LASTPIN (-1350 3500) $PN N7
J 0
(-1340 3510);
DISPLAY 0.617021 (-1340 3510);
PAINT ORANGE (-1340 3510);
FORCEPROP 2 LASTPIN (-1350 3400) $PN T7
J 0
(-1340 3410);
DISPLAY 0.617021 (-1340 3410);
PAINT ORANGE (-1340 3410);
FORCEPROP 2 LASTPIN (-1350 3350) $PN R8
J 0
(-1340 3360);
DISPLAY 0.617021 (-1340 3360);
PAINT ORANGE (-1340 3360);
FORCEPROP 2 LASTPIN (-1350 3300) $PN M6
J 0
(-1340 3310);
DISPLAY 0.617021 (-1340 3310);
PAINT ORANGE (-1340 3310);
FORCEPROP 2 LASTPIN (-1350 3250) $PN L8
J 0
(-1340 3260);
DISPLAY 0.617021 (-1340 3260);
PAINT ORANGE (-1340 3260);
FORCEPROP 2 LASTPIN (-1350 3150) $PN P8
J 0
(-1340 3160);
DISPLAY 0.617021 (-1340 3160);
PAINT ORANGE (-1340 3160);
FORCEPROP 2 LASTPIN (-1350 3100) $PN T8
J 0
(-1340 3110);
DISPLAY 0.617021 (-1340 3110);
PAINT ORANGE (-1340 3110);
FORCEPROP 2 LASTPIN (-1350 3050) $PN N8
J 0
(-1340 3060);
DISPLAY 0.617021 (-1340 3060);
PAINT ORANGE (-1340 3060);
FORCEPROP 2 LASTPIN (-1350 3000) $PN L9
J 0
(-1340 3010);
DISPLAY 0.617021 (-1340 3010);
PAINT ORANGE (-1340 3010);
FORCEPROP 2 LASTPIN (-1350 2850) $PN T9
J 0
(-1340 2860);
DISPLAY 0.617021 (-1340 2860);
PAINT ORANGE (-1340 2860);
FORCEPROP 2 LASTPIN (-1350 2800) $PN P9
J 0
(-1340 2810);
DISPLAY 0.617021 (-1340 2810);
PAINT ORANGE (-1340 2810);
FORCEPROP 2 LASTPIN (-1350 2750) $PN M8
J 0
(-1340 2760);
DISPLAY 0.617021 (-1340 2760);
PAINT ORANGE (-1340 2760);
FORCEPROP 2 LASTPIN (-1350 2700) $PN N9
J 0
(-1340 2710);
DISPLAY 0.617021 (-1340 2710);
PAINT ORANGE (-1340 2710);
FORCEPROP 2 LASTPIN (-1350 2600) $PN R9
J 0
(-1340 2610);
DISPLAY 0.617021 (-1340 2610);
PAINT ORANGE (-1340 2610);
FORCEPROP 2 LASTPIN (-1350 2550) $PN T10
J 0
(-1340 2560);
DISPLAY 0.617021 (-1340 2560);
PAINT ORANGE (-1340 2560);
FORCEPROP 2 LASTPIN (-1350 2300) $PN R10
J 0
(-1340 2310);
DISPLAY 0.617021 (-1340 2310);
PAINT ORANGE (-1340 2310);
FORCEPROP 2 LASTPIN (-1350 2250) $PN N10
J 0
(-1340 2260);
DISPLAY 0.617021 (-1340 2260);
PAINT ORANGE (-1340 2260);
FORCEPROP 2 LASTPIN (-1350 2200) $PN M11
J 0
(-1340 2210);
DISPLAY 0.617021 (-1340 2210);
PAINT ORANGE (-1340 2210);
FORCEPROP 2 LASTPIN (-1350 2100) $PN T11
J 0
(-1340 2110);
DISPLAY 0.617021 (-1340 2110);
PAINT ORANGE (-1340 2110);
FORCEPROP 2 LASTPIN (-1350 2050) $PN P11
J 0
(-1340 2060);
DISPLAY 0.617021 (-1340 2060);
PAINT ORANGE (-1340 2060);
FORCEPROP 2 LASTPIN (-1350 2000) $PN M10
J 0
(-1340 2010);
DISPLAY 0.617021 (-1340 2010);
PAINT ORANGE (-1340 2010);
FORCEPROP 2 LASTPIN (-1350 1950) $PN N11
J 0
(-1340 1960);
DISPLAY 0.617021 (-1340 1960);
PAINT ORANGE (-1340 1960);
FORCEPROP 2 LASTPIN (-1350 1850) $PN R11
J 0
(-1340 1860);
DISPLAY 0.617021 (-1340 1860);
PAINT ORANGE (-1340 1860);
FORCEPROP 2 LASTPIN (-1350 1800) $PN T12
J 0
(-1340 1810);
DISPLAY 0.617021 (-1340 1810);
PAINT ORANGE (-1340 1810);
FORCEPROP 2 LASTPIN (-1350 1750) $PN R13
J 0
(-1340 1760);
DISPLAY 0.617021 (-1340 1760);
PAINT ORANGE (-1340 1760);
FORCEPROP 2 LASTPIN (-1350 1700) $PN T14
J 0
(-1340 1710);
DISPLAY 0.617021 (-1340 1710);
PAINT ORANGE (-1340 1710);
FORCEPROP 2 LASTPIN (-1350 1600) $PN P12
J 0
(-1340 1610);
DISPLAY 0.617021 (-1340 1610);
PAINT ORANGE (-1340 1610);
FORCEPROP 2 LASTPIN (-1350 1550) $PN T13
J 0
(-1340 1560);
DISPLAY 0.617021 (-1340 1560);
PAINT ORANGE (-1340 1560);
FORCEPROP 2 LASTPIN (-1350 1450) $PN R12
J 0
(-1340 1460);
DISPLAY 0.617021 (-1340 1460);
PAINT ORANGE (-1340 1460);
FORCEPROP 2 LASTPIN (-1350 1400) $PN P13
J 0
(-1340 1410);
DISPLAY 0.617021 (-1340 1410);
PAINT ORANGE (-1340 1410);
FORCEPROP 2 LASTPIN (-1350 1350) $PN T15
J 0
(-1340 1360);
DISPLAY 0.617021 (-1340 1360);
PAINT ORANGE (-1340 1360);
FORCEPROP 2 LASTPIN (-1350 1300) $PN R14
J 0
(-1340 1310);
DISPLAY 0.617021 (-1340 1310);
PAINT ORANGE (-1340 1310);
FORCEPROP 2 LASTPIN (-2550 4550) $PN D3
J 2
(-2560 4560);
DISPLAY 0.617021 (-2560 4560);
PAINT ORANGE (-2560 4560);
FORCEPROP 2 LASTPIN (-2550 4500) $PN D1
J 2
(-2560 4510);
DISPLAY 0.617021 (-2560 4510);
PAINT ORANGE (-2560 4510);
FORCEPROP 2 LASTPIN (-2550 4450) $PN B1
J 2
(-2560 4460);
DISPLAY 0.617021 (-2560 4460);
PAINT ORANGE (-2560 4460);
FORCEPROP 2 LASTPIN (-2550 4400) $PN C2
J 2
(-2560 4410);
DISPLAY 0.617021 (-2560 4410);
PAINT ORANGE (-2560 4410);
FORCEPROP 2 LASTPIN (-2550 4300) $PN E2
J 2
(-2560 4310);
DISPLAY 0.617021 (-2560 4310);
PAINT ORANGE (-2560 4310);
FORCEPROP 2 LASTPIN (-2550 4250) $PN E3
J 2
(-2560 4260);
DISPLAY 0.617021 (-2560 4260);
PAINT ORANGE (-2560 4260);
FORCEPROP 2 LASTPIN (-2550 4200) $PN C1
J 2
(-2560 4210);
DISPLAY 0.617021 (-2560 4210);
PAINT ORANGE (-2560 4210);
FORCEPROP 2 LASTPIN (-2550 4150) $PN D2
J 2
(-2560 4160);
DISPLAY 0.617021 (-2560 4160);
PAINT ORANGE (-2560 4160);
FORCEPROP 2 LASTPIN (-2550 4050) $PN E1
J 2
(-2560 4060);
DISPLAY 0.617021 (-2560 4060);
PAINT ORANGE (-2560 4060);
FORCEPROP 2 LASTPIN (-2550 4000) $PN F2
J 2
(-2560 4010);
DISPLAY 0.617021 (-2560 4010);
PAINT ORANGE (-2560 4010);
FORCEPROP 2 LASTPIN (-2550 3950) $PN F4
J 2
(-2560 3960);
DISPLAY 0.617021 (-2560 3960);
PAINT ORANGE (-2560 3960);
FORCEPROP 2 LASTPIN (-2550 3900) $PN G6
J 2
(-2560 3910);
DISPLAY 0.617021 (-2560 3910);
PAINT ORANGE (-2560 3910);
FORCEPROP 2 LASTPIN (-2550 3800) $PN F3
J 2
(-2560 3810);
DISPLAY 0.617021 (-2560 3810);
PAINT ORANGE (-2560 3810);
FORCEPROP 2 LASTPIN (-2550 3750) $PN F1
J 2
(-2560 3760);
DISPLAY 0.617021 (-2560 3760);
PAINT ORANGE (-2560 3760);
FORCEPROP 2 LASTPIN (-2550 3700) $PN G5
J 2
(-2560 3710);
DISPLAY 0.617021 (-2560 3710);
PAINT ORANGE (-2560 3710);
FORCEPROP 2 LASTPIN (-2550 3650) $PN G4
J 2
(-2560 3660);
DISPLAY 0.617021 (-2560 3660);
PAINT ORANGE (-2560 3660);
FORCEPROP 2 LASTPIN (-2550 3550) $PN G2
J 2
(-2560 3560);
DISPLAY 0.617021 (-2560 3560);
PAINT ORANGE (-2560 3560);
FORCEPROP 2 LASTPIN (-2550 3500) $PN G3
J 2
(-2560 3510);
DISPLAY 0.617021 (-2560 3510);
PAINT ORANGE (-2560 3510);
FORCEPROP 2 LASTPIN (-2550 3450) $PN F5
J 2
(-2560 3460);
DISPLAY 0.617021 (-2560 3460);
PAINT ORANGE (-2560 3460);
FORCEPROP 2 LASTPIN (-2550 3300) $PN G1
J 2
(-2560 3310);
DISPLAY 0.617021 (-2560 3310);
PAINT ORANGE (-2560 3310);
FORCEPROP 2 LASTPIN (-2550 3250) $PN H2
J 2
(-2560 3260);
DISPLAY 0.617021 (-2560 3260);
PAINT ORANGE (-2560 3260);
FORCEPROP 2 LASTPIN (-2550 3200) $PN H4
J 2
(-2560 3210);
DISPLAY 0.617021 (-2560 3210);
PAINT ORANGE (-2560 3210);
FORCEPROP 2 LASTPIN (-2550 3150) $PN J6
J 2
(-2560 3160);
DISPLAY 0.617021 (-2560 3160);
PAINT ORANGE (-2560 3160);
FORCEPROP 2 LASTPIN (-2550 3050) $PN H3
J 2
(-2560 3060);
DISPLAY 0.617021 (-2560 3060);
PAINT ORANGE (-2560 3060);
FORCEPROP 2 LASTPIN (-2550 3000) $PN H1
J 2
(-2560 3010);
DISPLAY 0.617021 (-2560 3010);
PAINT ORANGE (-2560 3010);
FORCEPROP 2 LASTPIN (-2550 2900) $PN J3
J 2
(-2560 2910);
DISPLAY 0.617021 (-2560 2910);
PAINT ORANGE (-2560 2910);
FORCEPROP 2 LASTPIN (-2550 2800) $PN J2
J 2
(-2560 2810);
DISPLAY 0.617021 (-2560 2810);
PAINT ORANGE (-2560 2810);
FORCEPROP 2 LASTPIN (-2550 2750) $PN K1
J 2
(-2560 2760);
DISPLAY 0.617021 (-2560 2760);
PAINT ORANGE (-2560 2760);
FORCEPROP 2 LASTPIN (-2550 2700) $PN H5
J 2
(-2560 2710);
DISPLAY 0.617021 (-2560 2710);
PAINT ORANGE (-2560 2710);
FORCEPROP 2 LASTPIN (-2550 2650) $PN J4
J 2
(-2560 2660);
DISPLAY 0.617021 (-2560 2660);
PAINT ORANGE (-2560 2660);
FORCEPROP 2 LASTPIN (-2550 2550) $PN K3
J 2
(-2560 2560);
DISPLAY 0.617021 (-2560 2560);
PAINT ORANGE (-2560 2560);
FORCEPROP 2 LASTPIN (-2550 2500) $PN K2
J 2
(-2560 2510);
DISPLAY 0.617021 (-2560 2510);
PAINT ORANGE (-2560 2510);
FORCEPROP 2 LASTPIN (-2550 2450) $PN J5
J 2
(-2560 2460);
DISPLAY 0.617021 (-2560 2460);
PAINT ORANGE (-2560 2460);
FORCEPROP 2 LASTPIN (-2550 2400) $PN K6
J 2
(-2560 2410);
DISPLAY 0.617021 (-2560 2410);
PAINT ORANGE (-2560 2410);
FORCEPROP 2 LASTPIN (-2550 2300) $PN L1
J 2
(-2560 2310);
DISPLAY 0.617021 (-2560 2310);
PAINT ORANGE (-2560 2310);
FORCEPROP 2 LASTPIN (-2550 2250) $PN L3
J 2
(-2560 2260);
DISPLAY 0.617021 (-2560 2260);
PAINT ORANGE (-2560 2260);
FORCEPROP 2 LASTPIN (-2550 2200) $PN K4
J 2
(-2560 2210);
DISPLAY 0.617021 (-2560 2210);
PAINT ORANGE (-2560 2210);
FORCEPROP 2 LASTPIN (-2550 2150) $PN L5
J 2
(-2560 2160);
DISPLAY 0.617021 (-2560 2160);
PAINT ORANGE (-2560 2160);
FORCEPROP 2 LASTPIN (-2550 2050) $PN L2
J 2
(-2560 2060);
DISPLAY 0.617021 (-2560 2060);
PAINT ORANGE (-2560 2060);
FORCEPROP 2 LASTPIN (-2550 2000) $PN M1
J 2
(-2560 2010);
DISPLAY 0.617021 (-2560 2010);
PAINT ORANGE (-2560 2010);
FORCEPROP 2 LASTPIN (-2550 1950) $PN K5
J 2
(-2560 1960);
DISPLAY 0.617021 (-2560 1960);
PAINT ORANGE (-2560 1960);
FORCEPROP 2 LASTPIN (-2550 1900) $PN L4
J 2
(-2560 1910);
DISPLAY 0.617021 (-2560 1910);
PAINT ORANGE (-2560 1910);
FORCEPROP 2 LASTPIN (-2550 1800) $PN M3
J 2
(-2560 1810);
DISPLAY 0.617021 (-2560 1810);
PAINT ORANGE (-2560 1810);
FORCEPROP 2 LASTPIN (-2550 1750) $PN N1
J 2
(-2560 1760);
DISPLAY 0.617021 (-2560 1760);
PAINT ORANGE (-2560 1760);
FORCEPROP 2 LASTPIN (-2550 1700) $PN N2
J 2
(-2560 1710);
DISPLAY 0.617021 (-2560 1710);
PAINT ORANGE (-2560 1710);
FORCEPROP 2 LASTPIN (-2550 1650) $PN P1
J 2
(-2560 1660);
DISPLAY 0.617021 (-2560 1660);
PAINT ORANGE (-2560 1660);
FORCEPROP 2 LASTPIN (-2550 1550) $PN M2
J 2
(-2560 1560);
DISPLAY 0.617021 (-2560 1560);
PAINT ORANGE (-2560 1560);
FORCEPROP 2 LASTPIN (-2550 1500) $PN N3
J 2
(-2560 1510);
DISPLAY 0.617021 (-2560 1510);
PAINT ORANGE (-2560 1510);
FORCEPROP 2 LASTPIN (-2550 1450) $PN R1
J 2
(-2560 1460);
DISPLAY 0.617021 (-2560 1460);
PAINT ORANGE (-2560 1460);
FORCEPROP 2 LASTPIN (-2550 1400) $PN P2
J 2
(-2560 1410);
DISPLAY 0.617021 (-2560 1410);
PAINT ORANGE (-2560 1410);
FORCEPROP 1 LAST MATERIAL IC
J 0
(-2500 4731);
DISPLAY 0.617021 (-2500 4731);
PAINT SKYBLUE (-2500 4731);
FORCEPROP 1 LAST PART_NUMBER H63395-001
J 0
(-2500 1150);
DISPLAY 0.617021 (-2500 1150);
PAINT BLUE (-2500 1150);
FORCEPROP 1 LAST LOCATION U8D7
J 0
(-2500 4781);
DISPLAY 0.617021 (-2500 4781);
PAINT AQUA (-2500 4781);
FORCEPROP 0 LAST BOM_COST CPLD
J 0
(-2500 5000);
DISPLAY 1.361702 (-2500 5000);
PAINT ORANGE (-2500 5000);
DISPLAY INVISIBLE (-2500 5000);
FORCEPROP 2 LAST CDS_LOCATION U8D7
J 0
(-2500 4781);
DISPLAY 0.617021 (-2500 4781);
PAINT AQUA (-2500 4781);
DISPLAY INVISIBLE (-2500 4781);
FORCEPROP 1 LAST PATH I179
J 0
(-1524 4726);
PAINT GREEN (-1524 4726);
DISPLAY INVISIBLE (-1524 4726);
FORCEPROP 1 LAST CDS_LMAN_SYM_OUTLINE -550,1750,550,-1750
J 0
(-1950 2950);
DISPLAY 0.468085 (-1950 2950);
PAINT GREEN (-1950 2950);
DISPLAY INVISIBLE (-1950 2950);
FORCEPROP 2 LAST CDS_LIB mstr_memory
J 0
(-1950 2950);
PAINT ORANGE (-1950 2950);
DISPLAY INVISIBLE (-1950 2950);
FORCEPROP 2 LAST SEC 1
J 0
(-2500 4825);
DISPLAY 0.680851 (-2500 4825);
PAINT MONO (-2500 4825);
DISPLAY INVISIBLE (-2500 4825);
FORCEPROP 2 LAST SEC_TYPE 256BGA
J 0
(-2500 4825);
DISPLAY 1.021277 (-2500 4825);
PAINT ORANGE (-2500 4825);
DISPLAY INVISIBLE (-2500 4825);
FORCEPROP 0 LAST ROOM CPLD
J 0
(-2500 4900);
DISPLAY 1.361702 (-2500 4900);
PAINT ORANGE (-2500 4900);
DISPLAY INVISIBLE (-2500 4900);
FORCEPROP 1 LAST PACK_TYPE 256BGA
J 0
(-2500 4825);
PAINT SKYBLUE (-2500 4825);
DISPLAY INVISIBLE (-2500 4825);
FORCEADD OFFPAGE..2
(550 1350);
FORCEPROP 2 LAST $XR0 96 
J 0
(739 1350);
DISPLAY 0.638298 (739 1350);
PAINT MONO (739 1350);
FORCEPROP 2 LAST PATH I220
J 0
(725 1425);
DISPLAY 1.021277 (725 1425);
PAINT ORANGE (725 1425);
DISPLAY INVISIBLE (725 1425);
FORCEPROP 1 LAST COMMENT_BODY TRUE
J 0
(505 1255);
DISPLAY 1.170213 (505 1255);
PAINT GREEN (505 1255);
DISPLAY INVISIBLE (505 1255);
FORCEPROP 1 LAST OFFPAGE TRUE
J 0
(875 1225);
DISPLAY 1.170213 (875 1225);
PAINT GREEN (875 1225);
DISPLAY INVISIBLE (875 1225);
FORCEPROP 2 LAST CDS_LIB mstr_standard
J 2
(550 1350);
PAINT ORANGE (550 1350);
DISPLAY INVISIBLE (550 1350);
FORCEADD OFFPAGE..4
(550 1450);
FORCEPROP 2 LAST $XR0 55 
J 0
(736 1450);
DISPLAY 0.638298 (736 1450);
PAINT MONO (736 1450);
FORCEPROP 2 LAST PATH I221
J 0
(725 1525);
DISPLAY 1.021277 (725 1525);
PAINT ORANGE (725 1525);
DISPLAY INVISIBLE (725 1525);
FORCEPROP 1 LAST COMMENT_BODY TRUE
J 0
(525 1350);
DISPLAY 1.170213 (525 1350);
PAINT GREEN (525 1350);
DISPLAY INVISIBLE (525 1350);
FORCEPROP 1 LAST OFFPAGE TRUE
J 0
(875 1325);
DISPLAY 1.170213 (875 1325);
PAINT GREEN (875 1325);
DISPLAY INVISIBLE (875 1325);
FORCEPROP 2 LAST CDS_LIB mstr_standard
J 0
(550 1450);
PAINT ORANGE (550 1450);
DISPLAY INVISIBLE (550 1450);
FORCEADD OFFPAGE..4
(550 1800);
FORCEPROP 2 LAST $XR3 144 
J 0
(1066 1800);
DISPLAY 0.638298 (1066 1800);
PAINT MONO (1066 1800);
FORCEPROP 2 LAST $XR2 118 
J 0
(946 1800);
DISPLAY 0.638298 (946 1800);
PAINT MONO (946 1800);
FORCEPROP 2 LAST $XR1 112 
J 0
(826 1800);
DISPLAY 0.638298 (826 1800);
PAINT MONO (826 1800);
FORCEPROP 2 LAST $XR0 55 
J 0
(736 1800);
DISPLAY 0.638298 (736 1800);
PAINT MONO (736 1800);
FORCEPROP 2 LAST PATH I224
J 0
(725 1875);
DISPLAY 1.021277 (725 1875);
PAINT ORANGE (725 1875);
DISPLAY INVISIBLE (725 1875);
FORCEPROP 1 LAST COMMENT_BODY TRUE
J 0
(525 1700);
DISPLAY 1.170213 (525 1700);
PAINT GREEN (525 1700);
DISPLAY INVISIBLE (525 1700);
FORCEPROP 1 LAST OFFPAGE TRUE
J 0
(875 1675);
DISPLAY 1.170213 (875 1675);
PAINT GREEN (875 1675);
DISPLAY INVISIBLE (875 1675);
FORCEPROP 2 LAST CDS_LIB mstr_standard
J 2
(550 1800);
PAINT ORANGE (550 1800);
DISPLAY INVISIBLE (550 1800);
FORCEADD OFFPAGE..4
(550 1950);
FORCEPROP 2 LAST $XR0 111 
J 0
(736 1950);
DISPLAY 0.638298 (736 1950);
PAINT MONO (736 1950);
FORCEPROP 2 LAST PATH I225
J 0
(725 2025);
DISPLAY 1.021277 (725 2025);
PAINT ORANGE (725 2025);
DISPLAY INVISIBLE (725 2025);
FORCEPROP 1 LAST COMMENT_BODY TRUE
J 0
(525 1850);
DISPLAY 1.170213 (525 1850);
PAINT GREEN (525 1850);
DISPLAY INVISIBLE (525 1850);
FORCEPROP 1 LAST OFFPAGE TRUE
J 0
(875 1825);
DISPLAY 1.170213 (875 1825);
PAINT GREEN (875 1825);
DISPLAY INVISIBLE (875 1825);
FORCEPROP 2 LAST CDS_LIB mstr_standard
J 2
(550 1950);
PAINT ORANGE (550 1950);
DISPLAY INVISIBLE (550 1950);
FORCEADD OFFPAGE..4
(550 2200);
FORCEPROP 2 LAST $XR0 111 
J 0
(736 2200);
DISPLAY 0.638298 (736 2200);
PAINT MONO (736 2200);
FORCEPROP 2 LAST PATH I226
J 0
(725 2275);
DISPLAY 1.021277 (725 2275);
PAINT ORANGE (725 2275);
DISPLAY INVISIBLE (725 2275);
FORCEPROP 1 LAST COMMENT_BODY TRUE
J 0
(525 2100);
DISPLAY 1.170213 (525 2100);
PAINT GREEN (525 2100);
DISPLAY INVISIBLE (525 2100);
FORCEPROP 1 LAST OFFPAGE TRUE
J 0
(875 2075);
DISPLAY 1.170213 (875 2075);
PAINT GREEN (875 2075);
DISPLAY INVISIBLE (875 2075);
FORCEPROP 2 LAST CDS_LIB mstr_standard
J 0
(550 2200);
PAINT ORANGE (550 2200);
DISPLAY INVISIBLE (550 2200);
FORCEADD OFFPAGE..2
(550 2300);
FORCEPROP 2 LAST $XR0 190 
J 0
(739 2300);
DISPLAY 0.638298 (739 2300);
PAINT MONO (739 2300);
FORCEPROP 2 LAST PATH I227
J 0
(725 2375);
DISPLAY 1.021277 (725 2375);
PAINT ORANGE (725 2375);
DISPLAY INVISIBLE (725 2375);
FORCEPROP 1 LAST COMMENT_BODY TRUE
J 0
(505 2205);
DISPLAY 1.170213 (505 2205);
PAINT GREEN (505 2205);
DISPLAY INVISIBLE (505 2205);
FORCEPROP 1 LAST OFFPAGE TRUE
J 0
(875 2175);
DISPLAY 1.170213 (875 2175);
PAINT GREEN (875 2175);
DISPLAY INVISIBLE (875 2175);
FORCEPROP 2 LAST CDS_LIB mstr_standard
J 2
(550 2300);
PAINT ORANGE (550 2300);
DISPLAY INVISIBLE (550 2300);
FORCEADD OFFPAGE..2
(550 2750);
FORCEPROP 2 LAST $XR0 193 
J 0
(739 2750);
DISPLAY 0.638298 (739 2750);
PAINT MONO (739 2750);
FORCEPROP 2 LAST PATH I231
J 0
(725 2825);
DISPLAY 1.021277 (725 2825);
PAINT ORANGE (725 2825);
DISPLAY INVISIBLE (725 2825);
FORCEPROP 1 LAST COMMENT_BODY TRUE
J 0
(505 2655);
DISPLAY 1.170213 (505 2655);
PAINT GREEN (505 2655);
DISPLAY INVISIBLE (505 2655);
FORCEPROP 1 LAST OFFPAGE TRUE
J 0
(875 2625);
DISPLAY 1.170213 (875 2625);
PAINT GREEN (875 2625);
DISPLAY INVISIBLE (875 2625);
FORCEPROP 2 LAST CDS_LIB mstr_standard
J 0
(550 2750);
PAINT ORANGE (550 2750);
DISPLAY INVISIBLE (550 2750);
FORCEADD OFFPAGE..2
(550 3400);
FORCEPROP 2 LAST $XR0 213 
J 0
(739 3400);
DISPLAY 0.638298 (739 3400);
PAINT MONO (739 3400);
FORCEPROP 2 LAST PATH I234
J 0
(725 3475);
DISPLAY 1.021277 (725 3475);
PAINT ORANGE (725 3475);
DISPLAY INVISIBLE (725 3475);
FORCEPROP 1 LAST COMMENT_BODY TRUE
J 0
(505 3305);
DISPLAY 1.170213 (505 3305);
PAINT GREEN (505 3305);
DISPLAY INVISIBLE (505 3305);
FORCEPROP 1 LAST OFFPAGE TRUE
J 0
(875 3275);
DISPLAY 1.170213 (875 3275);
PAINT GREEN (875 3275);
DISPLAY INVISIBLE (875 3275);
FORCEPROP 2 LAST CDS_LIB mstr_standard
J 0
(550 3400);
PAINT ORANGE (550 3400);
DISPLAY INVISIBLE (550 3400);
FORCEADD OFFPAGE..2
(550 3550);
FORCEPROP 2 LAST $XR0 211 
J 0
(739 3550);
DISPLAY 0.638298 (739 3550);
PAINT MONO (739 3550);
FORCEPROP 2 LAST PATH I235
J 0
(725 3625);
DISPLAY 1.021277 (725 3625);
PAINT ORANGE (725 3625);
DISPLAY INVISIBLE (725 3625);
FORCEPROP 1 LAST COMMENT_BODY TRUE
J 0
(505 3455);
DISPLAY 1.170213 (505 3455);
PAINT GREEN (505 3455);
DISPLAY INVISIBLE (505 3455);
FORCEPROP 1 LAST OFFPAGE TRUE
J 0
(875 3425);
DISPLAY 1.170213 (875 3425);
PAINT GREEN (875 3425);
DISPLAY INVISIBLE (875 3425);
FORCEPROP 2 LAST CDS_LIB mstr_standard
J 0
(550 3550);
PAINT ORANGE (550 3550);
DISPLAY INVISIBLE (550 3550);
FORCEADD OFFPAGE..2
(550 3600);
FORCEPROP 2 LAST $XR0 193 
J 0
(739 3600);
DISPLAY 0.638298 (739 3600);
PAINT MONO (739 3600);
FORCEPROP 2 LAST PATH I236
J 0
(725 3675);
DISPLAY 1.021277 (725 3675);
PAINT ORANGE (725 3675);
DISPLAY INVISIBLE (725 3675);
FORCEPROP 1 LAST COMMENT_BODY TRUE
J 0
(505 3505);
DISPLAY 1.170213 (505 3505);
PAINT GREEN (505 3505);
DISPLAY INVISIBLE (505 3505);
FORCEPROP 1 LAST OFFPAGE TRUE
J 0
(875 3475);
DISPLAY 1.170213 (875 3475);
PAINT GREEN (875 3475);
DISPLAY INVISIBLE (875 3475);
FORCEPROP 2 LAST CDS_LIB mstr_standard
J 0
(550 3600);
PAINT ORANGE (550 3600);
DISPLAY INVISIBLE (550 3600);
FORCEADD OFFPAGE..4
(550 3800);
FORCEPROP 2 LAST $XR0 194 
J 0
(736 3800);
DISPLAY 0.638298 (736 3800);
PAINT MONO (736 3800);
FORCEPROP 2 LAST PATH I237
J 0
(725 3875);
DISPLAY 1.021277 (725 3875);
PAINT ORANGE (725 3875);
DISPLAY INVISIBLE (725 3875);
FORCEPROP 1 LAST COMMENT_BODY TRUE
J 0
(525 3700);
DISPLAY 1.170213 (525 3700);
PAINT GREEN (525 3700);
DISPLAY INVISIBLE (525 3700);
FORCEPROP 1 LAST OFFPAGE TRUE
J 0
(875 3675);
DISPLAY 1.170213 (875 3675);
PAINT GREEN (875 3675);
DISPLAY INVISIBLE (875 3675);
FORCEPROP 2 LAST CDS_LIB mstr_standard
J 0
(550 3800);
PAINT ORANGE (550 3800);
DISPLAY INVISIBLE (550 3800);
FORCEADD OFFPAGE..4
(550 4150);
FORCEPROP 2 LAST $XR0 193 
J 0
(736 4150);
DISPLAY 0.638298 (736 4150);
PAINT MONO (736 4150);
FORCEPROP 2 LAST PATH I239
J 0
(725 4225);
DISPLAY 1.021277 (725 4225);
PAINT ORANGE (725 4225);
DISPLAY INVISIBLE (725 4225);
FORCEPROP 1 LAST COMMENT_BODY TRUE
J 0
(525 4050);
DISPLAY 1.170213 (525 4050);
PAINT GREEN (525 4050);
DISPLAY INVISIBLE (525 4050);
FORCEPROP 1 LAST OFFPAGE TRUE
J 0
(875 4025);
DISPLAY 1.170213 (875 4025);
PAINT GREEN (875 4025);
DISPLAY INVISIBLE (875 4025);
FORCEPROP 2 LAST CDS_LIB mstr_standard
J 0
(550 4150);
PAINT ORANGE (550 4150);
DISPLAY INVISIBLE (550 4150);
FORCEADD OFFPAGE..4
(550 4300);
FORCEPROP 2 LAST $XR0 194 
J 0
(736 4300);
DISPLAY 0.638298 (736 4300);
PAINT MONO (736 4300);
FORCEPROP 2 LAST PATH I240
J 0
(725 4375);
DISPLAY 1.021277 (725 4375);
PAINT ORANGE (725 4375);
DISPLAY INVISIBLE (725 4375);
FORCEPROP 1 LAST COMMENT_BODY TRUE
J 0
(525 4200);
DISPLAY 1.170213 (525 4200);
PAINT GREEN (525 4200);
DISPLAY INVISIBLE (525 4200);
FORCEPROP 1 LAST OFFPAGE TRUE
J 0
(875 4175);
DISPLAY 1.170213 (875 4175);
PAINT GREEN (875 4175);
DISPLAY INVISIBLE (875 4175);
FORCEPROP 2 LAST CDS_LIB mstr_standard
J 0
(550 4300);
PAINT ORANGE (550 4300);
DISPLAY INVISIBLE (550 4300);
FORCEADD OFFPAGE..4
(550 4550);
FORCEPROP 2 LAST $XR0 206 
J 0
(736 4550);
DISPLAY 0.638298 (736 4550);
PAINT MONO (736 4550);
FORCEPROP 2 LAST PATH I241
J 0
(725 4625);
DISPLAY 1.021277 (725 4625);
PAINT ORANGE (725 4625);
DISPLAY INVISIBLE (725 4625);
FORCEPROP 1 LAST COMMENT_BODY TRUE
J 0
(525 4450);
DISPLAY 1.170213 (525 4450);
PAINT GREEN (525 4450);
DISPLAY INVISIBLE (525 4450);
FORCEPROP 1 LAST OFFPAGE TRUE
J 0
(875 4425);
DISPLAY 1.170213 (875 4425);
PAINT GREEN (875 4425);
DISPLAY INVISIBLE (875 4425);
FORCEPROP 2 LAST CDS_LIB mstr_standard
J 0
(550 4550);
PAINT ORANGE (550 4550);
DISPLAY INVISIBLE (550 4550);
FORCEADD OFFPAGE..4
R 2
(-4475 4400);
FORCEPROP 2 LAST $XR1 133 
J 0
(-4847 4400);
DISPLAY 0.638298 (-4847 4400);
PAINT MONO (-4847 4400);
FORCEPROP 2 LAST $XR0 119 
J 0
(-4727 4400);
DISPLAY 0.638298 (-4727 4400);
PAINT MONO (-4727 4400);
FORCEPROP 2 LAST PATH I243
J 0
(-4425 4475);
DISPLAY 1.021277 (-4425 4475);
PAINT ORANGE (-4425 4475);
DISPLAY INVISIBLE (-4425 4475);
FORCEPROP 1 LAST COMMENT_BODY TRUE
J 2
(-4450 4300);
DISPLAY 0.872340 (-4450 4300);
PAINT GREEN (-4450 4300);
DISPLAY INVISIBLE (-4450 4300);
FORCEPROP 1 LAST OFFPAGE TRUE
J 2
(-4800 4275);
DISPLAY 0.872340 (-4800 4275);
PAINT GREEN (-4800 4275);
DISPLAY INVISIBLE (-4800 4275);
FORCEPROP 2 LAST CDS_LIB mstr_standard
J 0
(-4475 4400);
PAINT ORANGE (-4475 4400);
DISPLAY INVISIBLE (-4475 4400);
FORCEADD OFFPAGE..2
R 2
(-4475 1500);
FORCEPROP 2 LAST $XR1 29 
J 0
(-4820 1500);
DISPLAY 0.638298 (-4820 1500);
PAINT MONO (-4820 1500);
FORCEPROP 2 LAST $XR0 192 
J 0
(-4730 1500);
DISPLAY 0.638298 (-4730 1500);
PAINT MONO (-4730 1500);
FORCEPROP 2 LAST PATH I244
J 0
(-4425 1575);
DISPLAY 1.021277 (-4425 1575);
PAINT ORANGE (-4425 1575);
DISPLAY INVISIBLE (-4425 1575);
FORCEPROP 1 LAST COMMENT_BODY TRUE
J 2
(-4430 1405);
DISPLAY 1.170213 (-4430 1405);
PAINT GREEN (-4430 1405);
DISPLAY INVISIBLE (-4430 1405);
FORCEPROP 1 LAST OFFPAGE TRUE
J 2
(-4800 1375);
DISPLAY 1.170213 (-4800 1375);
PAINT GREEN (-4800 1375);
DISPLAY INVISIBLE (-4800 1375);
FORCEPROP 2 LAST CDS_LIB mstr_standard
J 0
(-4475 1500);
PAINT ORANGE (-4475 1500);
DISPLAY INVISIBLE (-4475 1500);
FORCEADD OFFPAGE..4
R 2
(-4475 1750);
FORCEPROP 2 LAST $XR0 206 
J 0
(-4727 1750);
DISPLAY 0.638298 (-4727 1750);
PAINT MONO (-4727 1750);
FORCEPROP 2 LAST PATH I246
J 0
(-4425 1825);
DISPLAY 1.021277 (-4425 1825);
PAINT ORANGE (-4425 1825);
DISPLAY INVISIBLE (-4425 1825);
FORCEPROP 1 LAST COMMENT_BODY TRUE
J 2
(-4450 1650);
DISPLAY 1.170213 (-4450 1650);
PAINT GREEN (-4450 1650);
DISPLAY INVISIBLE (-4450 1650);
FORCEPROP 1 LAST OFFPAGE TRUE
J 2
(-4800 1625);
DISPLAY 1.170213 (-4800 1625);
PAINT GREEN (-4800 1625);
DISPLAY INVISIBLE (-4800 1625);
FORCEPROP 2 LAST CDS_LIB mstr_standard
J 0
(-4475 1750);
PAINT ORANGE (-4475 1750);
DISPLAY INVISIBLE (-4475 1750);
FORCEADD OFFPAGE..2
R 2
(-4475 1800);
FORCEPROP 2 LAST $XR0 108 
J 0
(-4730 1800);
DISPLAY 0.638298 (-4730 1800);
PAINT MONO (-4730 1800);
FORCEPROP 2 LAST PATH I248
J 0
(-4425 1875);
DISPLAY 1.021277 (-4425 1875);
PAINT ORANGE (-4425 1875);
DISPLAY INVISIBLE (-4425 1875);
FORCEPROP 1 LAST COMMENT_BODY TRUE
J 2
(-4430 1705);
DISPLAY 1.170213 (-4430 1705);
PAINT GREEN (-4430 1705);
DISPLAY INVISIBLE (-4430 1705);
FORCEPROP 1 LAST OFFPAGE TRUE
J 2
(-4800 1675);
DISPLAY 1.170213 (-4800 1675);
PAINT GREEN (-4800 1675);
DISPLAY INVISIBLE (-4800 1675);
FORCEPROP 2 LAST CDS_LIB mstr_standard
J 0
(-4475 1800);
PAINT ORANGE (-4475 1800);
DISPLAY INVISIBLE (-4475 1800);
FORCEADD OFFPAGE..2
R 2
(-4475 2150);
FORCEPROP 2 LAST $XR0 96 
J 0
(-4699 2150);
DISPLAY 0.638298 (-4699 2150);
PAINT MONO (-4699 2150);
FORCEPROP 2 LAST PATH I252
J 0
(-4425 2225);
DISPLAY 1.021277 (-4425 2225);
PAINT ORANGE (-4425 2225);
DISPLAY INVISIBLE (-4425 2225);
FORCEPROP 1 LAST COMMENT_BODY TRUE
J 2
(-4430 2055);
DISPLAY 1.170213 (-4430 2055);
PAINT GREEN (-4430 2055);
DISPLAY INVISIBLE (-4430 2055);
FORCEPROP 1 LAST OFFPAGE TRUE
J 2
(-4800 2025);
DISPLAY 1.170213 (-4800 2025);
PAINT GREEN (-4800 2025);
DISPLAY INVISIBLE (-4800 2025);
FORCEPROP 2 LAST CDS_LIB mstr_standard
J 0
(-4475 2150);
PAINT ORANGE (-4475 2150);
DISPLAY INVISIBLE (-4475 2150);
FORCEADD OFFPAGE..4
R 2
(-4475 2300);
FORCEPROP 2 LAST $XR0 201 
J 0
(-4727 2300);
DISPLAY 0.638298 (-4727 2300);
PAINT MONO (-4727 2300);
FORCEPROP 2 LAST PATH I255
J 0
(-4425 2375);
DISPLAY 1.021277 (-4425 2375);
PAINT ORANGE (-4425 2375);
DISPLAY INVISIBLE (-4425 2375);
FORCEPROP 1 LAST COMMENT_BODY TRUE
J 2
(-4450 2200);
DISPLAY 1.170213 (-4450 2200);
PAINT GREEN (-4450 2200);
DISPLAY INVISIBLE (-4450 2200);
FORCEPROP 1 LAST OFFPAGE TRUE
J 2
(-4800 2175);
DISPLAY 1.170213 (-4800 2175);
PAINT GREEN (-4800 2175);
DISPLAY INVISIBLE (-4800 2175);
FORCEPROP 2 LAST CDS_LIB mstr_standard
J 0
(-4475 2300);
PAINT ORANGE (-4475 2300);
DISPLAY INVISIBLE (-4475 2300);
FORCEADD OFFPAGE..4
R 2
(-4475 2800);
FORCEPROP 2 LAST $XR0 144 
J 0
(-4727 2800);
DISPLAY 0.638298 (-4727 2800);
PAINT MONO (-4727 2800);
FORCEPROP 2 LAST PATH I260
J 0
(-4425 2875);
DISPLAY 1.021277 (-4425 2875);
PAINT ORANGE (-4425 2875);
DISPLAY INVISIBLE (-4425 2875);
FORCEPROP 1 LAST COMMENT_BODY TRUE
J 2
(-4450 2700);
DISPLAY 0.872340 (-4450 2700);
PAINT GREEN (-4450 2700);
DISPLAY INVISIBLE (-4450 2700);
FORCEPROP 1 LAST OFFPAGE TRUE
J 2
(-4800 2675);
DISPLAY 0.872340 (-4800 2675);
PAINT GREEN (-4800 2675);
DISPLAY INVISIBLE (-4800 2675);
FORCEPROP 2 LAST CDS_LIB mstr_standard
J 0
(-4475 2800);
PAINT ORANGE (-4475 2800);
DISPLAY INVISIBLE (-4475 2800);
FORCEADD OFFPAGE..2
R 2
(-4475 2750);
FORCEPROP 2 LAST $XR0 194 
J 0
(-4730 2750);
DISPLAY 0.638298 (-4730 2750);
PAINT MONO (-4730 2750);
FORCEPROP 2 LAST PATH I261
J 0
(-4425 2825);
DISPLAY 1.021277 (-4425 2825);
PAINT ORANGE (-4425 2825);
DISPLAY INVISIBLE (-4425 2825);
FORCEPROP 1 LAST COMMENT_BODY TRUE
J 2
(-4430 2655);
DISPLAY 1.170213 (-4430 2655);
PAINT GREEN (-4430 2655);
DISPLAY INVISIBLE (-4430 2655);
FORCEPROP 1 LAST OFFPAGE TRUE
J 2
(-4800 2625);
DISPLAY 1.170213 (-4800 2625);
PAINT GREEN (-4800 2625);
DISPLAY INVISIBLE (-4800 2625);
FORCEPROP 2 LAST CDS_LIB mstr_standard
J 0
(-4475 2750);
PAINT ORANGE (-4475 2750);
DISPLAY INVISIBLE (-4475 2750);
FORCEADD OFFPAGE..4
R 2
(-4475 2950);
FORCEPROP 2 LAST $XR0 144 
J 0
(-4727 2950);
DISPLAY 0.638298 (-4727 2950);
PAINT MONO (-4727 2950);
FORCEPROP 2 LAST PATH I263
J 0
(-4425 3025);
DISPLAY 1.021277 (-4425 3025);
PAINT ORANGE (-4425 3025);
DISPLAY INVISIBLE (-4425 3025);
FORCEPROP 1 LAST COMMENT_BODY TRUE
J 2
(-4450 2850);
DISPLAY 1.170213 (-4450 2850);
PAINT GREEN (-4450 2850);
DISPLAY INVISIBLE (-4450 2850);
FORCEPROP 1 LAST OFFPAGE TRUE
J 2
(-4800 2825);
DISPLAY 1.170213 (-4800 2825);
PAINT GREEN (-4800 2825);
DISPLAY INVISIBLE (-4800 2825);
FORCEPROP 2 LAST CDS_LIB mstr_standard
J 0
(-4475 2950);
PAINT ORANGE (-4475 2950);
DISPLAY INVISIBLE (-4475 2950);
FORCEADD OFFPAGE..2
R 2
(-4475 3250);
FORCEPROP 2 LAST $XR0 194 
J 0
(-4730 3250);
DISPLAY 0.638298 (-4730 3250);
PAINT MONO (-4730 3250);
FORCEPROP 2 LAST PATH I267
J 0
(-4425 3325);
DISPLAY 1.021277 (-4425 3325);
PAINT ORANGE (-4425 3325);
DISPLAY INVISIBLE (-4425 3325);
FORCEPROP 1 LAST COMMENT_BODY TRUE
J 2
(-4430 3155);
DISPLAY 1.170213 (-4430 3155);
PAINT GREEN (-4430 3155);
DISPLAY INVISIBLE (-4430 3155);
FORCEPROP 1 LAST OFFPAGE TRUE
J 2
(-4800 3125);
DISPLAY 1.170213 (-4800 3125);
PAINT GREEN (-4800 3125);
DISPLAY INVISIBLE (-4800 3125);
FORCEPROP 2 LAST CDS_LIB mstr_standard
J 0
(-4475 3250);
PAINT ORANGE (-4475 3250);
DISPLAY INVISIBLE (-4475 3250);
FORCEADD OFFPAGE..4
R 2
(-4475 3300);
FORCEPROP 2 LAST $XR1 148 
J 0
(-4847 3300);
DISPLAY 0.638298 (-4847 3300);
PAINT MONO (-4847 3300);
FORCEPROP 2 LAST $XR0 118 
J 0
(-4727 3300);
DISPLAY 0.638298 (-4727 3300);
PAINT MONO (-4727 3300);
FORCEPROP 2 LAST PATH I268
J 0
(-4425 3375);
DISPLAY 1.021277 (-4425 3375);
PAINT ORANGE (-4425 3375);
DISPLAY INVISIBLE (-4425 3375);
FORCEPROP 1 LAST COMMENT_BODY TRUE
J 2
(-4450 3200);
DISPLAY 1.170213 (-4450 3200);
PAINT GREEN (-4450 3200);
DISPLAY INVISIBLE (-4450 3200);
FORCEPROP 1 LAST OFFPAGE TRUE
J 2
(-4800 3175);
DISPLAY 1.170213 (-4800 3175);
PAINT GREEN (-4800 3175);
DISPLAY INVISIBLE (-4800 3175);
FORCEPROP 2 LAST CDS_LIB mstr_standard
J 0
(-4475 3300);
PAINT ORANGE (-4475 3300);
DISPLAY INVISIBLE (-4475 3300);
FORCEADD OFFPAGE..4
R 2
(-4475 3400);
FORCEPROP 2 LAST $XR1 175 
J 0
(-4847 3400);
DISPLAY 0.638298 (-4847 3400);
PAINT MONO (-4847 3400);
FORCEPROP 2 LAST $XR0 196 
J 0
(-4727 3400);
DISPLAY 0.638298 (-4727 3400);
PAINT MONO (-4727 3400);
FORCEPROP 2 LAST PATH I269
J 0
(-4425 3475);
DISPLAY 1.021277 (-4425 3475);
PAINT ORANGE (-4425 3475);
DISPLAY INVISIBLE (-4425 3475);
FORCEPROP 1 LAST COMMENT_BODY TRUE
J 2
(-4450 3300);
DISPLAY 1.170213 (-4450 3300);
PAINT GREEN (-4450 3300);
DISPLAY INVISIBLE (-4450 3300);
FORCEPROP 1 LAST OFFPAGE TRUE
J 2
(-4800 3275);
DISPLAY 1.170213 (-4800 3275);
PAINT GREEN (-4800 3275);
DISPLAY INVISIBLE (-4800 3275);
FORCEPROP 2 LAST CDS_LIB mstr_standard
J 0
(-4475 3400);
PAINT ORANGE (-4475 3400);
DISPLAY INVISIBLE (-4475 3400);
FORCEADD OFFPAGE..2
R 2
(-4475 3450);
FORCEPROP 2 LAST $XR1 146 
J 0
(-4850 3450);
DISPLAY 0.638298 (-4850 3450);
PAINT MONO (-4850 3450);
FORCEPROP 2 LAST $XR0 120 
J 0
(-4730 3450);
DISPLAY 0.638298 (-4730 3450);
PAINT MONO (-4730 3450);
FORCEPROP 2 LAST PATH I270
J 0
(-4425 3525);
DISPLAY 1.021277 (-4425 3525);
PAINT ORANGE (-4425 3525);
DISPLAY INVISIBLE (-4425 3525);
FORCEPROP 1 LAST COMMENT_BODY TRUE
J 2
(-4430 3355);
DISPLAY 1.170213 (-4430 3355);
PAINT GREEN (-4430 3355);
DISPLAY INVISIBLE (-4430 3355);
FORCEPROP 1 LAST OFFPAGE TRUE
J 2
(-4800 3325);
DISPLAY 1.170213 (-4800 3325);
PAINT GREEN (-4800 3325);
DISPLAY INVISIBLE (-4800 3325);
FORCEPROP 2 LAST CDS_LIB mstr_standard
J 0
(-4475 3450);
PAINT ORANGE (-4475 3450);
DISPLAY INVISIBLE (-4475 3450);
FORCEADD OFFPAGE..4
R 2
(-4475 3500);
FORCEPROP 2 LAST $XR1 113 
J 0
(-4816 3500);
DISPLAY 0.638298 (-4816 3500);
PAINT MONO (-4816 3500);
FORCEPROP 2 LAST $XR0 21 
J 0
(-4696 3500);
DISPLAY 0.638298 (-4696 3500);
PAINT MONO (-4696 3500);
FORCEPROP 2 LAST PATH I271
J 0
(-4425 3575);
DISPLAY 1.021277 (-4425 3575);
PAINT ORANGE (-4425 3575);
DISPLAY INVISIBLE (-4425 3575);
FORCEPROP 1 LAST COMMENT_BODY TRUE
J 2
(-4450 3400);
DISPLAY 1.170213 (-4450 3400);
PAINT GREEN (-4450 3400);
DISPLAY INVISIBLE (-4450 3400);
FORCEPROP 1 LAST OFFPAGE TRUE
J 2
(-4800 3375);
DISPLAY 1.170213 (-4800 3375);
PAINT GREEN (-4800 3375);
DISPLAY INVISIBLE (-4800 3375);
FORCEPROP 2 LAST CDS_LIB mstr_standard
J 0
(-4475 3500);
PAINT ORANGE (-4475 3500);
DISPLAY INVISIBLE (-4475 3500);
FORCEADD OFFPAGE..3
R 2
(-4475 3650);
FORCEPROP 2 LAST $XR0 190 
J 0
(-4755 3650);
DISPLAY 0.638298 (-4755 3650);
PAINT MONO (-4755 3650);
FORCEPROP 2 LAST PATH I272
J 0
(-4425 3725);
DISPLAY 1.021277 (-4425 3725);
PAINT ORANGE (-4425 3725);
DISPLAY INVISIBLE (-4425 3725);
FORCEPROP 1 LAST COMMENT_BODY TRUE
J 2
(-4425 3550);
DISPLAY 0.872340 (-4425 3550);
PAINT GREEN (-4425 3550);
DISPLAY INVISIBLE (-4425 3550);
FORCEPROP 1 LAST OFFPAGE TRUE
J 2
(-4800 3525);
DISPLAY 0.872340 (-4800 3525);
PAINT GREEN (-4800 3525);
DISPLAY INVISIBLE (-4800 3525);
FORCEPROP 2 LAST CDS_LIB mstr_standard
J 0
(-4475 3650);
PAINT ORANGE (-4475 3650);
DISPLAY INVISIBLE (-4475 3650);
FORCEADD OFFPAGE..4
R 2
(-4475 3550);
FORCEPROP 2 LAST $XR0 21 
J 0
(-4696 3550);
DISPLAY 0.638298 (-4696 3550);
PAINT MONO (-4696 3550);
FORCEPROP 2 LAST PATH I273
J 0
(-4425 3625);
DISPLAY 1.021277 (-4425 3625);
PAINT ORANGE (-4425 3625);
DISPLAY INVISIBLE (-4425 3625);
FORCEPROP 1 LAST COMMENT_BODY TRUE
J 2
(-4450 3450);
DISPLAY 1.170213 (-4450 3450);
PAINT GREEN (-4450 3450);
DISPLAY INVISIBLE (-4450 3450);
FORCEPROP 1 LAST OFFPAGE TRUE
J 2
(-4800 3425);
DISPLAY 1.170213 (-4800 3425);
PAINT GREEN (-4800 3425);
DISPLAY INVISIBLE (-4800 3425);
FORCEPROP 2 LAST CDS_LIB mstr_standard
J 0
(-4475 3550);
PAINT ORANGE (-4475 3550);
DISPLAY INVISIBLE (-4475 3550);
FORCEADD OFFPAGE..2
R 2
(-4475 3700);
FORCEPROP 2 LAST $XR2 247 
J 0
(-4970 3700);
DISPLAY 0.638298 (-4970 3700);
PAINT MONO (-4970 3700);
FORCEPROP 2 LAST $XR1 155 
J 0
(-4850 3700);
DISPLAY 0.638298 (-4850 3700);
PAINT MONO (-4850 3700);
FORCEPROP 2 LAST $XR0 111 
J 0
(-4730 3700);
DISPLAY 0.638298 (-4730 3700);
PAINT MONO (-4730 3700);
FORCEPROP 2 LAST $XR3 175 
J 0
(-4970 3700);
DISPLAY 0.638298 (-4970 3700);
PAINT MONO (-4970 3700);
FORCEPROP 2 LAST PATH I274
J 0
(-4425 3775);
DISPLAY 1.021277 (-4425 3775);
PAINT ORANGE (-4425 3775);
DISPLAY INVISIBLE (-4425 3775);
FORCEPROP 1 LAST COMMENT_BODY TRUE
J 2
(-4430 3605);
DISPLAY 0.872340 (-4430 3605);
PAINT GREEN (-4430 3605);
DISPLAY INVISIBLE (-4430 3605);
FORCEPROP 1 LAST OFFPAGE TRUE
J 2
(-4800 3575);
DISPLAY 0.872340 (-4800 3575);
PAINT GREEN (-4800 3575);
DISPLAY INVISIBLE (-4800 3575);
FORCEPROP 2 LAST CDS_LIB mstr_standard
J 0
(-4475 3700);
PAINT ORANGE (-4475 3700);
DISPLAY INVISIBLE (-4475 3700);
FORCEADD OFFPAGE..4
R 2
(-4475 3750);
FORCEPROP 2 LAST $XR0 21 
J 0
(-4696 3750);
DISPLAY 0.638298 (-4696 3750);
PAINT MONO (-4696 3750);
FORCEPROP 2 LAST $XR1 147 
J 0
(-4696 3750);
DISPLAY 0.638298 (-4696 3750);
PAINT MONO (-4696 3750);
FORCEPROP 2 LAST PATH I275
J 0
(-4425 3825);
DISPLAY 1.021277 (-4425 3825);
PAINT ORANGE (-4425 3825);
DISPLAY INVISIBLE (-4425 3825);
FORCEPROP 1 LAST COMMENT_BODY TRUE
J 2
(-4450 3650);
DISPLAY 1.170213 (-4450 3650);
PAINT GREEN (-4450 3650);
DISPLAY INVISIBLE (-4450 3650);
FORCEPROP 1 LAST OFFPAGE TRUE
J 2
(-4800 3625);
DISPLAY 1.170213 (-4800 3625);
PAINT GREEN (-4800 3625);
DISPLAY INVISIBLE (-4800 3625);
FORCEPROP 2 LAST CDS_LIB mstr_standard
J 0
(-4475 3750);
PAINT ORANGE (-4475 3750);
DISPLAY INVISIBLE (-4475 3750);
FORCEADD OFFPAGE..4
R 2
(-4475 3800);
FORCEPROP 2 LAST $XR0 21 
J 0
(-4696 3800);
DISPLAY 0.638298 (-4696 3800);
PAINT MONO (-4696 3800);
FORCEPROP 2 LAST $XR1 147 
J 0
(-4696 3800);
DISPLAY 0.638298 (-4696 3800);
PAINT MONO (-4696 3800);
FORCEPROP 2 LAST PATH I276
J 0
(-4425 3875);
DISPLAY 1.021277 (-4425 3875);
PAINT ORANGE (-4425 3875);
DISPLAY INVISIBLE (-4425 3875);
FORCEPROP 1 LAST COMMENT_BODY TRUE
J 2
(-4450 3700);
DISPLAY 1.170213 (-4450 3700);
PAINT GREEN (-4450 3700);
DISPLAY INVISIBLE (-4450 3700);
FORCEPROP 1 LAST OFFPAGE TRUE
J 2
(-4800 3675);
DISPLAY 1.170213 (-4800 3675);
PAINT GREEN (-4800 3675);
DISPLAY INVISIBLE (-4800 3675);
FORCEPROP 2 LAST CDS_LIB mstr_standard
J 0
(-4475 3800);
PAINT ORANGE (-4475 3800);
DISPLAY INVISIBLE (-4475 3800);
FORCEADD OFFPAGE..4
R 2
(-4475 3900);
FORCEPROP 2 LAST $XR2 145 
J 0
(-4967 3900);
DISPLAY 0.638298 (-4967 3900);
PAINT MONO (-4967 3900);
FORCEPROP 2 LAST $XR1 119 
J 0
(-4847 3900);
DISPLAY 0.638298 (-4847 3900);
PAINT MONO (-4847 3900);
FORCEPROP 2 LAST $XR0 175 
J 0
(-4727 3900);
DISPLAY 0.638298 (-4727 3900);
PAINT MONO (-4727 3900);
FORCEPROP 2 LAST PATH I277
J 0
(-4425 3975);
DISPLAY 1.021277 (-4425 3975);
PAINT ORANGE (-4425 3975);
DISPLAY INVISIBLE (-4425 3975);
FORCEPROP 1 LAST COMMENT_BODY TRUE
J 2
(-4450 3800);
DISPLAY 0.872340 (-4450 3800);
PAINT GREEN (-4450 3800);
DISPLAY INVISIBLE (-4450 3800);
FORCEPROP 1 LAST OFFPAGE TRUE
J 2
(-4800 3775);
DISPLAY 0.872340 (-4800 3775);
PAINT GREEN (-4800 3775);
DISPLAY INVISIBLE (-4800 3775);
FORCEPROP 2 LAST CDS_LIB mstr_standard
J 2
(-4475 3900);
PAINT ORANGE (-4475 3900);
DISPLAY INVISIBLE (-4475 3900);
FORCEADD OFFPAGE..4
R 2
(-4475 4050);
FORCEPROP 2 LAST $XR0 101 
J 0
(-4727 4050);
DISPLAY 0.638298 (-4727 4050);
PAINT MONO (-4727 4050);
FORCEPROP 2 LAST PATH I279
J 0
(-4425 4125);
DISPLAY 1.021277 (-4425 4125);
PAINT ORANGE (-4425 4125);
DISPLAY INVISIBLE (-4425 4125);
FORCEPROP 1 LAST COMMENT_BODY TRUE
J 2
(-4450 3950);
DISPLAY 1.170213 (-4450 3950);
PAINT GREEN (-4450 3950);
DISPLAY INVISIBLE (-4450 3950);
FORCEPROP 1 LAST OFFPAGE TRUE
J 2
(-4800 3925);
DISPLAY 1.170213 (-4800 3925);
PAINT GREEN (-4800 3925);
DISPLAY INVISIBLE (-4800 3925);
FORCEPROP 2 LAST CDS_LIB mstr_standard
J 0
(-4475 4050);
PAINT ORANGE (-4475 4050);
DISPLAY INVISIBLE (-4475 4050);
FORCEADD OFFPAGE..4
R 2
(-4475 4000);
FORCEPROP 2 LAST $XR0 21 
J 0
(-4696 4000);
DISPLAY 0.638298 (-4696 4000);
PAINT MONO (-4696 4000);
FORCEPROP 2 LAST PATH I280
J 0
(-4425 4075);
DISPLAY 1.021277 (-4425 4075);
PAINT ORANGE (-4425 4075);
DISPLAY INVISIBLE (-4425 4075);
FORCEPROP 1 LAST COMMENT_BODY TRUE
J 2
(-4450 3900);
DISPLAY 1.170213 (-4450 3900);
PAINT GREEN (-4450 3900);
DISPLAY INVISIBLE (-4450 3900);
FORCEPROP 1 LAST OFFPAGE TRUE
J 2
(-4800 3875);
DISPLAY 1.170213 (-4800 3875);
PAINT GREEN (-4800 3875);
DISPLAY INVISIBLE (-4800 3875);
FORCEPROP 2 LAST CDS_LIB mstr_standard
J 0
(-4475 4000);
PAINT ORANGE (-4475 4000);
DISPLAY INVISIBLE (-4475 4000);
FORCEADD OFFPAGE..2
R 2
(-4475 4300);
FORCEPROP 2 LAST $XR0 119 
J 0
(-4730 4300);
DISPLAY 0.638298 (-4730 4300);
PAINT MONO (-4730 4300);
FORCEPROP 2 LAST PATH I284
J 0
(-4425 4375);
DISPLAY 1.021277 (-4425 4375);
PAINT ORANGE (-4425 4375);
DISPLAY INVISIBLE (-4425 4375);
FORCEPROP 1 LAST COMMENT_BODY TRUE
J 2
(-4430 4205);
DISPLAY 1.170213 (-4430 4205);
PAINT GREEN (-4430 4205);
DISPLAY INVISIBLE (-4430 4205);
FORCEPROP 1 LAST OFFPAGE TRUE
J 2
(-4800 4175);
DISPLAY 1.170213 (-4800 4175);
PAINT GREEN (-4800 4175);
DISPLAY INVISIBLE (-4800 4175);
FORCEPROP 2 LAST CDS_LIB mstr_standard
J 2
(-4475 4300);
PAINT ORANGE (-4475 4300);
DISPLAY INVISIBLE (-4475 4300);
FORCEADD OFFPAGE..2
R 2
(-4475 4450);
FORCEPROP 2 LAST $XR0 121 
J 0
(-4730 4450);
DISPLAY 0.638298 (-4730 4450);
PAINT MONO (-4730 4450);
FORCEPROP 2 LAST PATH I285
J 0
(-4425 4525);
DISPLAY 1.021277 (-4425 4525);
PAINT ORANGE (-4425 4525);
DISPLAY INVISIBLE (-4425 4525);
FORCEPROP 1 LAST COMMENT_BODY TRUE
J 2
(-4430 4355);
DISPLAY 1.170213 (-4430 4355);
PAINT GREEN (-4430 4355);
DISPLAY INVISIBLE (-4430 4355);
FORCEPROP 1 LAST OFFPAGE TRUE
J 2
(-4800 4325);
DISPLAY 1.170213 (-4800 4325);
PAINT GREEN (-4800 4325);
DISPLAY INVISIBLE (-4800 4325);
FORCEPROP 2 LAST CDS_LIB mstr_standard
J 0
(-4475 4450);
PAINT ORANGE (-4475 4450);
DISPLAY INVISIBLE (-4475 4450);
FORCEADD OFFPAGE..4
R 2
(-4475 3950);
FORCEPROP 2 LAST $XR0 192 
J 0
(-4727 3950);
DISPLAY 0.638298 (-4727 3950);
PAINT MONO (-4727 3950);
FORCEPROP 2 LAST PATH I298
J 0
(-4425 4025);
DISPLAY 1.021277 (-4425 4025);
PAINT ORANGE (-4425 4025);
DISPLAY INVISIBLE (-4425 4025);
FORCEPROP 1 LAST COMMENT_BODY TRUE
J 2
(-4450 3850);
DISPLAY 1.170213 (-4450 3850);
PAINT GREEN (-4450 3850);
DISPLAY INVISIBLE (-4450 3850);
FORCEPROP 1 LAST OFFPAGE TRUE
J 2
(-4800 3825);
DISPLAY 1.170213 (-4800 3825);
PAINT GREEN (-4800 3825);
DISPLAY INVISIBLE (-4800 3825);
FORCEPROP 2 LAST CDS_LIB mstr_standard
J 0
(-4475 3950);
PAINT MONO (-4475 3950);
DISPLAY INVISIBLE (-4475 3950);
FORCEADD OFFPAGE..4
R 2
(-4475 3150);
FORCEPROP 2 LAST $XR0 196 
J 0
(-4727 3150);
DISPLAY 0.638298 (-4727 3150);
PAINT MONO (-4727 3150);
FORCEPROP 2 LAST PATH I299
J 0
(-4425 3225);
DISPLAY 1.021277 (-4425 3225);
PAINT ORANGE (-4425 3225);
DISPLAY INVISIBLE (-4425 3225);
FORCEPROP 1 LAST COMMENT_BODY TRUE
J 2
(-4450 3050);
DISPLAY 1.170213 (-4450 3050);
PAINT GREEN (-4450 3050);
DISPLAY INVISIBLE (-4450 3050);
FORCEPROP 1 LAST OFFPAGE TRUE
J 2
(-4800 3025);
DISPLAY 1.170213 (-4800 3025);
PAINT GREEN (-4800 3025);
DISPLAY INVISIBLE (-4800 3025);
FORCEPROP 2 LAST CDS_LIB mstr_standard
J 0
(-4475 3150);
PAINT MONO (-4475 3150);
DISPLAY INVISIBLE (-4475 3150);
FORCEADD OFFPAGE..2
R 2
(-4475 4200);
FORCEPROP 2 LAST $XR0 187 
J 0
(-4730 4200);
DISPLAY 0.638298 (-4730 4200);
PAINT MONO (-4730 4200);
FORCEPROP 2 LAST PATH I301
J 0
(-4425 4275);
DISPLAY 1.021277 (-4425 4275);
PAINT ORANGE (-4425 4275);
DISPLAY INVISIBLE (-4425 4275);
FORCEPROP 1 LAST COMMENT_BODY TRUE
J 2
(-4430 4105);
DISPLAY 1.170213 (-4430 4105);
PAINT GREEN (-4430 4105);
DISPLAY INVISIBLE (-4430 4105);
FORCEPROP 1 LAST OFFPAGE TRUE
J 2
(-4800 4075);
DISPLAY 1.170213 (-4800 4075);
PAINT GREEN (-4800 4075);
DISPLAY INVISIBLE (-4800 4075);
FORCEPROP 2 LAST CDS_LIB mstr_standard
J 0
(-4475 4200);
PAINT MONO (-4475 4200);
DISPLAY INVISIBLE (-4475 4200);
FORCEADD OFFPAGE..2
R 2
(-4475 3050);
FORCEPROP 2 LAST $XR0 187 
J 0
(-4730 3050);
DISPLAY 0.638298 (-4730 3050);
PAINT MONO (-4730 3050);
FORCEPROP 2 LAST PATH I302
J 0
(-4425 3125);
DISPLAY 1.021277 (-4425 3125);
PAINT ORANGE (-4425 3125);
DISPLAY INVISIBLE (-4425 3125);
FORCEPROP 1 LAST COMMENT_BODY TRUE
J 2
(-4430 2955);
DISPLAY 1.170213 (-4430 2955);
PAINT GREEN (-4430 2955);
DISPLAY INVISIBLE (-4430 2955);
FORCEPROP 1 LAST OFFPAGE TRUE
J 2
(-4800 2925);
DISPLAY 1.170213 (-4800 2925);
PAINT GREEN (-4800 2925);
DISPLAY INVISIBLE (-4800 2925);
FORCEPROP 2 LAST CDS_LIB mstr_standard
J 0
(-4475 3050);
PAINT MONO (-4475 3050);
DISPLAY INVISIBLE (-4475 3050);
FORCEADD OFFPAGE..2
R 2
(-4475 3000);
FORCEPROP 2 LAST $XR0 187 
J 0
(-4730 3000);
DISPLAY 0.638298 (-4730 3000);
PAINT MONO (-4730 3000);
FORCEPROP 2 LAST PATH I303
J 0
(-4425 3075);
DISPLAY 1.021277 (-4425 3075);
PAINT ORANGE (-4425 3075);
DISPLAY INVISIBLE (-4425 3075);
FORCEPROP 1 LAST COMMENT_BODY TRUE
J 2
(-4430 2905);
DISPLAY 1.170213 (-4430 2905);
PAINT GREEN (-4430 2905);
DISPLAY INVISIBLE (-4430 2905);
FORCEPROP 1 LAST OFFPAGE TRUE
J 2
(-4800 2875);
DISPLAY 1.170213 (-4800 2875);
PAINT GREEN (-4800 2875);
DISPLAY INVISIBLE (-4800 2875);
FORCEPROP 2 LAST CDS_LIB mstr_standard
J 0
(-4475 3000);
PAINT MONO (-4475 3000);
DISPLAY INVISIBLE (-4475 3000);
FORCEADD OFFPAGE..2
(550 2050);
FORCEPROP 2 LAST $XR2 158 
J 0
(979 2050);
DISPLAY 0.638298 (979 2050);
PAINT MONO (979 2050);
FORCEPROP 2 LAST $XR1 120 
J 0
(859 2050);
DISPLAY 0.638298 (859 2050);
PAINT MONO (859 2050);
FORCEPROP 2 LAST $XR0 147 
J 0
(739 2050);
DISPLAY 0.638298 (739 2050);
PAINT MONO (739 2050);
FORCEPROP 2 LAST PATH I304
J 0
(725 2125);
DISPLAY 1.021277 (725 2125);
PAINT ORANGE (725 2125);
DISPLAY INVISIBLE (725 2125);
FORCEPROP 1 LAST COMMENT_BODY TRUE
J 0
(505 1955);
DISPLAY 1.170213 (505 1955);
PAINT GREEN (505 1955);
DISPLAY INVISIBLE (505 1955);
FORCEPROP 1 LAST OFFPAGE TRUE
J 0
(875 1925);
DISPLAY 1.170213 (875 1925);
PAINT GREEN (875 1925);
DISPLAY INVISIBLE (875 1925);
FORCEPROP 2 LAST CDS_LIB mstr_standard
J 0
(550 2050);
PAINT MONO (550 2050);
DISPLAY INVISIBLE (550 2050);
FORCEADD OFFPAGE..2
(550 2600);
FORCEPROP 2 LAST $XR2 158 
J 0
(979 2600);
DISPLAY 0.638298 (979 2600);
PAINT MONO (979 2600);
FORCEPROP 2 LAST $XR1 120 
J 0
(859 2600);
DISPLAY 0.638298 (859 2600);
PAINT MONO (859 2600);
FORCEPROP 2 LAST $XR0 147 
J 0
(739 2600);
DISPLAY 0.638298 (739 2600);
PAINT MONO (739 2600);
FORCEPROP 2 LAST PATH I305
J 0
(725 2675);
DISPLAY 1.021277 (725 2675);
PAINT ORANGE (725 2675);
DISPLAY INVISIBLE (725 2675);
FORCEPROP 1 LAST COMMENT_BODY TRUE
J 0
(505 2505);
DISPLAY 1.170213 (505 2505);
PAINT GREEN (505 2505);
DISPLAY INVISIBLE (505 2505);
FORCEPROP 1 LAST OFFPAGE TRUE
J 0
(875 2475);
DISPLAY 1.170213 (875 2475);
PAINT GREEN (875 2475);
DISPLAY INVISIBLE (875 2475);
FORCEPROP 2 LAST CDS_LIB mstr_standard
J 0
(550 2600);
PAINT MONO (550 2600);
DISPLAY INVISIBLE (550 2600);
FORCEADD OFFPAGE..4
(550 3000);
FORCEPROP 2 LAST $XR1 120 
J 0
(856 3000);
DISPLAY 0.638298 (856 3000);
PAINT MONO (856 3000);
FORCEPROP 2 LAST $XR0 135 
J 0
(736 3000);
DISPLAY 0.638298 (736 3000);
PAINT MONO (736 3000);
FORCEPROP 2 LAST PATH I306
J 0
(725 3075);
DISPLAY 1.021277 (725 3075);
PAINT ORANGE (725 3075);
DISPLAY INVISIBLE (725 3075);
FORCEPROP 1 LAST COMMENT_BODY TRUE
J 0
(525 2900);
DISPLAY 1.170213 (525 2900);
PAINT GREEN (525 2900);
DISPLAY INVISIBLE (525 2900);
FORCEPROP 1 LAST OFFPAGE TRUE
J 0
(875 2875);
DISPLAY 1.170213 (875 2875);
PAINT GREEN (875 2875);
DISPLAY INVISIBLE (875 2875);
FORCEPROP 2 LAST CDS_LIB mstr_standard
J 0
(550 3000);
PAINT MONO (550 3000);
DISPLAY INVISIBLE (550 3000);
FORCEADD OFFPAGE..4
R 2
(-4475 1450);
FORCEPROP 2 LAST $XR2 157 
J 0
(-4967 1450);
DISPLAY 0.638298 (-4967 1450);
PAINT MONO (-4967 1450);
FORCEPROP 2 LAST $XR1 144 
J 0
(-4847 1450);
DISPLAY 0.638298 (-4847 1450);
PAINT MONO (-4847 1450);
FORCEPROP 2 LAST $XR0 119 
J 0
(-4727 1450);
DISPLAY 0.638298 (-4727 1450);
PAINT MONO (-4727 1450);
FORCEPROP 2 LAST PATH I307
J 0
(-4425 1525);
DISPLAY 1.021277 (-4425 1525);
PAINT ORANGE (-4425 1525);
DISPLAY INVISIBLE (-4425 1525);
FORCEPROP 1 LAST COMMENT_BODY TRUE
J 2
(-4450 1350);
DISPLAY 1.170213 (-4450 1350);
PAINT GREEN (-4450 1350);
DISPLAY INVISIBLE (-4450 1350);
FORCEPROP 1 LAST OFFPAGE TRUE
J 2
(-4800 1325);
DISPLAY 1.170213 (-4800 1325);
PAINT GREEN (-4800 1325);
DISPLAY INVISIBLE (-4800 1325);
FORCEPROP 2 LAST CDS_LIB mstr_standard
J 0
(-4475 1450);
PAINT MONO (-4475 1450);
DISPLAY INVISIBLE (-4475 1450);
FORCEADD OFFPAGE..2
(550 3050);
FORCEPROP 2 LAST $XR0 104 
J 0
(739 3050);
DISPLAY 0.638298 (739 3050);
PAINT MONO (739 3050);
FORCEPROP 2 LAST PATH I308
J 0
(725 3125);
DISPLAY 1.021277 (725 3125);
PAINT ORANGE (725 3125);
DISPLAY INVISIBLE (725 3125);
FORCEPROP 1 LAST COMMENT_BODY TRUE
J 0
(505 2955);
DISPLAY 1.170213 (505 2955);
PAINT GREEN (505 2955);
DISPLAY INVISIBLE (505 2955);
FORCEPROP 1 LAST OFFPAGE TRUE
J 0
(875 2925);
DISPLAY 1.170213 (875 2925);
PAINT GREEN (875 2925);
DISPLAY INVISIBLE (875 2925);
FORCEPROP 2 LAST CDS_LIB mstr_standard
J 0
(550 3050);
PAINT MONO (550 3050);
DISPLAY INVISIBLE (550 3050);
FORCEADD OFFPAGE..2
(550 2550);
FORCEPROP 2 LAST $XR0 104 
J 0
(739 2550);
DISPLAY 0.638298 (739 2550);
PAINT MONO (739 2550);
FORCEPROP 2 LAST PATH I309
J 0
(725 2625);
DISPLAY 1.021277 (725 2625);
PAINT ORANGE (725 2625);
DISPLAY INVISIBLE (725 2625);
FORCEPROP 1 LAST COMMENT_BODY TRUE
J 0
(505 2455);
DISPLAY 1.170213 (505 2455);
PAINT GREEN (505 2455);
DISPLAY INVISIBLE (505 2455);
FORCEPROP 1 LAST OFFPAGE TRUE
J 0
(875 2425);
DISPLAY 1.170213 (875 2425);
PAINT GREEN (875 2425);
DISPLAY INVISIBLE (875 2425);
FORCEPROP 2 LAST CDS_LIB mstr_standard
J 0
(550 2550);
PAINT MONO (550 2550);
DISPLAY INVISIBLE (550 2550);
FORCEADD OFFPAGE..4
R 2
(-4475 3200);
FORCEPROP 2 LAST $XR3 144 
J 0
(-5087 3200);
DISPLAY 0.638298 (-5087 3200);
PAINT MONO (-5087 3200);
FORCEPROP 2 LAST $XR2 120 
J 0
(-4967 3200);
DISPLAY 0.638298 (-4967 3200);
PAINT MONO (-4967 3200);
FORCEPROP 2 LAST $XR1 181 
J 0
(-4847 3200);
DISPLAY 0.638298 (-4847 3200);
PAINT MONO (-4847 3200);
FORCEPROP 2 LAST $XR0 157 
J 0
(-4727 3200);
DISPLAY 0.638298 (-4727 3200);
PAINT MONO (-4727 3200);
FORCEPROP 2 LAST PATH I312
J 0
(-4425 3275);
DISPLAY 1.021277 (-4425 3275);
PAINT ORANGE (-4425 3275);
DISPLAY INVISIBLE (-4425 3275);
FORCEPROP 1 LAST COMMENT_BODY TRUE
J 2
(-4450 3100);
DISPLAY 1.170213 (-4450 3100);
PAINT GREEN (-4450 3100);
DISPLAY INVISIBLE (-4450 3100);
FORCEPROP 1 LAST OFFPAGE TRUE
J 2
(-4800 3075);
DISPLAY 1.170213 (-4800 3075);
PAINT GREEN (-4800 3075);
DISPLAY INVISIBLE (-4800 3075);
FORCEPROP 2 LAST CDS_LIB mstr_standard
J 0
(-4475 3200);
PAINT MONO (-4475 3200);
DISPLAY INVISIBLE (-4475 3200);
FORCEADD OFFPAGE..4
(550 2700);
FORCEPROP 2 LAST $XR2 157 
J 0
(976 2700);
DISPLAY 0.638298 (976 2700);
PAINT MONO (976 2700);
FORCEPROP 2 LAST $XR1 147 
J 0
(856 2700);
DISPLAY 0.638298 (856 2700);
PAINT MONO (856 2700);
FORCEPROP 2 LAST $XR0 119 
J 0
(736 2700);
DISPLAY 0.638298 (736 2700);
PAINT MONO (736 2700);
FORCEPROP 2 LAST PATH I313
J 0
(725 2775);
DISPLAY 1.021277 (725 2775);
PAINT ORANGE (725 2775);
DISPLAY INVISIBLE (725 2775);
FORCEPROP 1 LAST COMMENT_BODY TRUE
J 0
(525 2600);
DISPLAY 1.170213 (525 2600);
PAINT GREEN (525 2600);
DISPLAY INVISIBLE (525 2600);
FORCEPROP 1 LAST OFFPAGE TRUE
J 0
(875 2575);
DISPLAY 1.170213 (875 2575);
PAINT GREEN (875 2575);
DISPLAY INVISIBLE (875 2575);
FORCEPROP 2 LAST CDS_LIB mstr_standard
J 0
(550 2700);
PAINT MONO (550 2700);
DISPLAY INVISIBLE (550 2700);
FORCEADD OFFPAGE..4
(550 2450);
FORCEPROP 2 LAST $XR2 144 
J 0
(976 2450);
DISPLAY 0.638298 (976 2450);
PAINT MONO (976 2450);
FORCEPROP 2 LAST $XR1 120 
J 0
(856 2450);
DISPLAY 0.638298 (856 2450);
PAINT MONO (856 2450);
FORCEPROP 2 LAST $XR0 168 
J 0
(736 2450);
DISPLAY 0.638298 (736 2450);
PAINT MONO (736 2450);
FORCEPROP 2 LAST PATH I314
J 0
(725 2525);
DISPLAY 1.021277 (725 2525);
PAINT ORANGE (725 2525);
DISPLAY INVISIBLE (725 2525);
FORCEPROP 1 LAST COMMENT_BODY TRUE
J 0
(525 2350);
DISPLAY 1.170213 (525 2350);
PAINT GREEN (525 2350);
DISPLAY INVISIBLE (525 2350);
FORCEPROP 1 LAST OFFPAGE TRUE
J 0
(875 2325);
DISPLAY 1.170213 (875 2325);
PAINT GREEN (875 2325);
DISPLAY INVISIBLE (875 2325);
FORCEPROP 2 LAST CDS_LIB mstr_standard
J 0
(550 2450);
PAINT ORANGE (550 2450);
DISPLAY INVISIBLE (550 2450);
FORCEADD OFFPAGE..2
(550 3100);
FORCEPROP 2 LAST $XR0 155 
J 0
(739 3100);
DISPLAY 0.638298 (739 3100);
PAINT MONO (739 3100);
FORCEPROP 2 LAST PATH I317
J 0
(725 3175);
DISPLAY 1.021277 (725 3175);
PAINT ORANGE (725 3175);
DISPLAY INVISIBLE (725 3175);
FORCEPROP 1 LAST COMMENT_BODY TRUE
J 0
(505 3005);
DISPLAY 1.170213 (505 3005);
PAINT GREEN (505 3005);
DISPLAY INVISIBLE (505 3005);
FORCEPROP 1 LAST OFFPAGE TRUE
J 0
(875 2975);
DISPLAY 1.170213 (875 2975);
PAINT GREEN (875 2975);
DISPLAY INVISIBLE (875 2975);
FORCEPROP 2 LAST CDS_LIB mstr_standard
J 0
(550 3100);
PAINT ORANGE (550 3100);
DISPLAY INVISIBLE (550 3100);
FORCEADD OFFPAGE..4
(550 2500);
FORCEPROP 2 LAST $XR0 135 
J 0
(736 2500);
DISPLAY 0.638298 (736 2500);
PAINT MONO (736 2500);
FORCEPROP 2 LAST PATH I318
J 0
(725 2575);
DISPLAY 1.021277 (725 2575);
PAINT ORANGE (725 2575);
DISPLAY INVISIBLE (725 2575);
FORCEPROP 1 LAST COMMENT_BODY TRUE
J 0
(525 2400);
DISPLAY 1.170213 (525 2400);
PAINT GREEN (525 2400);
DISPLAY INVISIBLE (525 2400);
FORCEPROP 1 LAST OFFPAGE TRUE
J 0
(875 2375);
DISPLAY 1.170213 (875 2375);
PAINT GREEN (875 2375);
DISPLAY INVISIBLE (875 2375);
FORCEPROP 2 LAST CDS_LIB mstr_standard
J 0
(550 2500);
PAINT ORANGE (550 2500);
DISPLAY INVISIBLE (550 2500);
FORCEADD OFFPAGE..4
(550 3250);
FORCEPROP 2 LAST $XR1 118 
J 0
(856 3250);
DISPLAY 0.638298 (856 3250);
PAINT MONO (856 3250);
FORCEPROP 2 LAST $XR0 211 
J 0
(736 3250);
DISPLAY 0.638298 (736 3250);
PAINT MONO (736 3250);
FORCEPROP 2 LAST PATH I319
J 0
(725 3325);
DISPLAY 1.021277 (725 3325);
PAINT ORANGE (725 3325);
DISPLAY INVISIBLE (725 3325);
FORCEPROP 1 LAST COMMENT_BODY TRUE
J 0
(525 3150);
DISPLAY 1.170213 (525 3150);
PAINT GREEN (525 3150);
DISPLAY INVISIBLE (525 3150);
FORCEPROP 1 LAST OFFPAGE TRUE
J 0
(875 3125);
DISPLAY 1.170213 (875 3125);
PAINT GREEN (875 3125);
DISPLAY INVISIBLE (875 3125);
FORCEPROP 2 LAST CDS_LIB mstr_standard
J 0
(550 3250);
PAINT ORANGE (550 3250);
DISPLAY INVISIBLE (550 3250);
FORCEADD OFFPAGE..4
R 2
(-4475 1550);
FORCEPROP 2 LAST $XR0 233 
J 0
(-4727 1550);
DISPLAY 0.638298 (-4727 1550);
PAINT MONO (-4727 1550);
FORCEPROP 2 LAST PATH I320
J 0
(-4425 1625);
DISPLAY 1.021277 (-4425 1625);
PAINT ORANGE (-4425 1625);
DISPLAY INVISIBLE (-4425 1625);
FORCEPROP 1 LAST COMMENT_BODY TRUE
J 2
(-4450 1450);
DISPLAY 1.170213 (-4450 1450);
PAINT GREEN (-4450 1450);
DISPLAY INVISIBLE (-4450 1450);
FORCEPROP 1 LAST OFFPAGE TRUE
J 2
(-4800 1425);
DISPLAY 1.170213 (-4800 1425);
PAINT GREEN (-4800 1425);
DISPLAY INVISIBLE (-4800 1425);
FORCEPROP 2 LAST CDS_LIB mstr_standard
J 0
(-4475 1550);
PAINT ORANGE (-4475 1550);
DISPLAY INVISIBLE (-4475 1550);
FORCEADD OFFPAGE..4
R 2
(-4475 1700);
FORCEPROP 2 LAST $XR0 234 
J 0
(-4727 1700);
DISPLAY 0.638298 (-4727 1700);
PAINT MONO (-4727 1700);
FORCEPROP 2 LAST PATH I321
J 0
(-4425 1775);
DISPLAY 1.021277 (-4425 1775);
PAINT ORANGE (-4425 1775);
DISPLAY INVISIBLE (-4425 1775);
FORCEPROP 1 LAST COMMENT_BODY TRUE
J 2
(-4450 1600);
DISPLAY 1.170213 (-4450 1600);
PAINT GREEN (-4450 1600);
DISPLAY INVISIBLE (-4450 1600);
FORCEPROP 1 LAST OFFPAGE TRUE
J 2
(-4800 1575);
DISPLAY 1.170213 (-4800 1575);
PAINT GREEN (-4800 1575);
DISPLAY INVISIBLE (-4800 1575);
FORCEPROP 2 LAST CDS_LIB mstr_standard
J 0
(-4475 1700);
PAINT ORANGE (-4475 1700);
DISPLAY INVISIBLE (-4475 1700);
FORCEADD OFFPAGE..4
(550 3500);
FORCEPROP 2 LAST $XR1 91 
J 0
(856 3500);
DISPLAY 0.638298 (856 3500);
PAINT MONO (856 3500);
FORCEPROP 2 LAST $XR0 231 
J 0
(736 3500);
DISPLAY 0.638298 (736 3500);
PAINT MONO (736 3500);
FORCEPROP 2 LAST PATH I322
J 0
(725 3575);
DISPLAY 1.021277 (725 3575);
PAINT ORANGE (725 3575);
DISPLAY INVISIBLE (725 3575);
FORCEPROP 1 LAST COMMENT_BODY TRUE
J 0
(525 3400);
DISPLAY 1.170213 (525 3400);
PAINT GREEN (525 3400);
DISPLAY INVISIBLE (525 3400);
FORCEPROP 1 LAST OFFPAGE TRUE
J 0
(875 3375);
DISPLAY 1.170213 (875 3375);
PAINT GREEN (875 3375);
DISPLAY INVISIBLE (875 3375);
FORCEPROP 2 LAST CDS_LIB mstr_standard
J 0
(550 3500);
PAINT ORANGE (550 3500);
DISPLAY INVISIBLE (550 3500);
FORCEADD OFFPAGE..4
(550 4000);
FORCEPROP 2 LAST $XR2 157 
J 0
(976 4000);
DISPLAY 0.638298 (976 4000);
PAINT MONO (976 4000);
FORCEPROP 2 LAST $XR1 145 
J 0
(856 4000);
DISPLAY 0.638298 (856 4000);
PAINT MONO (856 4000);
FORCEPROP 2 LAST $XR0 118 
J 0
(736 4000);
DISPLAY 0.638298 (736 4000);
PAINT MONO (736 4000);
FORCEPROP 2 LAST PATH I323
J 0
(725 4075);
DISPLAY 1.021277 (725 4075);
PAINT ORANGE (725 4075);
DISPLAY INVISIBLE (725 4075);
FORCEPROP 1 LAST COMMENT_BODY TRUE
J 0
(525 3900);
DISPLAY 1.170213 (525 3900);
PAINT GREEN (525 3900);
DISPLAY INVISIBLE (525 3900);
FORCEPROP 1 LAST OFFPAGE TRUE
J 0
(875 3875);
DISPLAY 1.170213 (875 3875);
PAINT GREEN (875 3875);
DISPLAY INVISIBLE (875 3875);
FORCEPROP 2 LAST CDS_LIB mstr_standard
J 0
(550 4000);
PAINT ORANGE (550 4000);
DISPLAY INVISIBLE (550 4000);
FORCEADD OFFPAGE..4
(550 3300);
FORCEPROP 2 LAST $XR0 232 
J 0
(736 3300);
DISPLAY 0.638298 (736 3300);
PAINT MONO (736 3300);
FORCEPROP 2 LAST PATH I324
J 0
(725 3375);
DISPLAY 1.021277 (725 3375);
PAINT ORANGE (725 3375);
DISPLAY INVISIBLE (725 3375);
FORCEPROP 1 LAST COMMENT_BODY TRUE
J 0
(525 3200);
DISPLAY 1.170213 (525 3200);
PAINT GREEN (525 3200);
DISPLAY INVISIBLE (525 3200);
FORCEPROP 1 LAST OFFPAGE TRUE
J 0
(875 3175);
DISPLAY 1.170213 (875 3175);
PAINT GREEN (875 3175);
DISPLAY INVISIBLE (875 3175);
FORCEPROP 2 LAST CDS_LIB mstr_standard
J 0
(550 3300);
PAINT ORANGE (550 3300);
DISPLAY INVISIBLE (550 3300);
FORCEADD OFFPAGE..4
R 2
(-4475 2050);
FORCEPROP 2 LAST $XR0 101 
J 0
(-4727 2050);
DISPLAY 0.638298 (-4727 2050);
PAINT MONO (-4727 2050);
FORCEPROP 2 LAST PATH I325
J 0
(-4425 2125);
DISPLAY 1.021277 (-4425 2125);
PAINT ORANGE (-4425 2125);
DISPLAY INVISIBLE (-4425 2125);
FORCEPROP 1 LAST COMMENT_BODY TRUE
J 2
(-4450 1950);
DISPLAY 1.170213 (-4450 1950);
PAINT GREEN (-4450 1950);
DISPLAY INVISIBLE (-4450 1950);
FORCEPROP 1 LAST OFFPAGE TRUE
J 2
(-4800 1925);
DISPLAY 1.170213 (-4800 1925);
PAINT GREEN (-4800 1925);
DISPLAY INVISIBLE (-4800 1925);
FORCEPROP 2 LAST CDS_LIB mstr_standard
J 0
(-4475 2050);
PAINT ORANGE (-4475 2050);
DISPLAY INVISIBLE (-4475 2050);
FORCEADD OFFPAGE..4
R 2
(-4475 1950);
FORCEPROP 2 LAST $XR1 112 
J 0
(-4847 1950);
DISPLAY 0.638298 (-4847 1950);
PAINT MONO (-4847 1950);
FORCEPROP 2 LAST $XR0 201 
J 0
(-4727 1950);
DISPLAY 0.638298 (-4727 1950);
PAINT MONO (-4727 1950);
FORCEPROP 2 LAST PATH I326
J 0
(-4425 2025);
DISPLAY 1.021277 (-4425 2025);
PAINT ORANGE (-4425 2025);
DISPLAY INVISIBLE (-4425 2025);
FORCEPROP 1 LAST COMMENT_BODY TRUE
J 2
(-4450 1850);
DISPLAY 1.170213 (-4450 1850);
PAINT GREEN (-4450 1850);
DISPLAY INVISIBLE (-4450 1850);
FORCEPROP 1 LAST OFFPAGE TRUE
J 2
(-4800 1825);
DISPLAY 1.170213 (-4800 1825);
PAINT GREEN (-4800 1825);
DISPLAY INVISIBLE (-4800 1825);
FORCEPROP 2 LAST CDS_LIB mstr_standard
J 0
(-4475 1950);
PAINT ORANGE (-4475 1950);
DISPLAY INVISIBLE (-4475 1950);
FORCEADD OFFPAGE..4
R 2
(-4475 1900);
FORCEPROP 2 LAST $XR0 193 
J 0
(-4727 1900);
DISPLAY 0.638298 (-4727 1900);
PAINT MONO (-4727 1900);
FORCEPROP 2 LAST PATH I327
J 0
(-4425 1975);
DISPLAY 1.021277 (-4425 1975);
PAINT ORANGE (-4425 1975);
DISPLAY INVISIBLE (-4425 1975);
FORCEPROP 1 LAST COMMENT_BODY TRUE
J 2
(-4450 1800);
DISPLAY 1.170213 (-4450 1800);
PAINT GREEN (-4450 1800);
DISPLAY INVISIBLE (-4450 1800);
FORCEPROP 1 LAST OFFPAGE TRUE
J 2
(-4800 1775);
DISPLAY 1.170213 (-4800 1775);
PAINT GREEN (-4800 1775);
DISPLAY INVISIBLE (-4800 1775);
FORCEPROP 2 LAST CDS_LIB mstr_standard
J 0
(-4475 1900);
PAINT ORANGE (-4475 1900);
DISPLAY INVISIBLE (-4475 1900);
FORCEADD OFFPAGE..4
(550 1550);
FORCEPROP 2 LAST $XR2 120 
J 0
(946 1550);
DISPLAY 0.638298 (946 1550);
PAINT MONO (946 1550);
FORCEPROP 2 LAST $XR1 147 
J 0
(826 1550);
DISPLAY 0.638298 (826 1550);
PAINT MONO (826 1550);
FORCEPROP 2 LAST $XR0 92 
J 0
(736 1550);
DISPLAY 0.638298 (736 1550);
PAINT MONO (736 1550);
FORCEPROP 2 LAST PATH I328
J 0
(725 1625);
DISPLAY 1.021277 (725 1625);
PAINT ORANGE (725 1625);
DISPLAY INVISIBLE (725 1625);
FORCEPROP 1 LAST COMMENT_BODY TRUE
J 0
(525 1450);
DISPLAY 1.170213 (525 1450);
PAINT GREEN (525 1450);
DISPLAY INVISIBLE (525 1450);
FORCEPROP 1 LAST OFFPAGE TRUE
J 0
(875 1425);
DISPLAY 1.170213 (875 1425);
PAINT GREEN (875 1425);
DISPLAY INVISIBLE (875 1425);
FORCEPROP 2 LAST CDS_LIB mstr_standard
J 0
(550 1550);
PAINT ORANGE (550 1550);
DISPLAY INVISIBLE (550 1550);
FORCEADD OFFPAGE..4
R 2
(-4475 2200);
FORCEPROP 2 LAST $XR0 144 
J 0
(-4727 2200);
DISPLAY 0.638298 (-4727 2200);
PAINT MONO (-4727 2200);
FORCEPROP 2 LAST PATH I329
J 0
(-4725 2250);
DISPLAY 1.021277 (-4725 2250);
PAINT ORANGE (-4725 2250);
DISPLAY INVISIBLE (-4725 2250);
FORCEPROP 1 LAST COMMENT_BODY TRUE
J 2
(-4450 2100);
DISPLAY 1.170213 (-4450 2100);
PAINT GREEN (-4450 2100);
DISPLAY INVISIBLE (-4450 2100);
FORCEPROP 1 LAST OFFPAGE TRUE
J 2
(-4800 2075);
DISPLAY 1.170213 (-4800 2075);
PAINT GREEN (-4800 2075);
DISPLAY INVISIBLE (-4800 2075);
FORCEPROP 2 LAST CDS_LIB mstr_standard
J 0
(-4475 2200);
PAINT ORANGE (-4475 2200);
DISPLAY INVISIBLE (-4475 2200);
FORCEADD OFFPAGE..1
(-4475 2700);
FORCEPROP 2 LAST $XR2 183 
J 0
(-4967 2700);
DISPLAY 0.638298 (-4967 2700);
PAINT MONO (-4967 2700);
FORCEPROP 2 LAST $XR1 108 
J 0
(-4847 2700);
DISPLAY 0.638298 (-4847 2700);
PAINT MONO (-4847 2700);
FORCEPROP 2 LAST $XR0 138 
J 0
(-4727 2700);
DISPLAY 0.638298 (-4727 2700);
PAINT MONO (-4727 2700);
FORCEPROP 2 LAST PATH I330
J 0
(-4425 2775);
DISPLAY 1.021277 (-4425 2775);
PAINT ORANGE (-4425 2775);
DISPLAY INVISIBLE (-4425 2775);
FORCEPROP 1 LAST COMMENT_BODY TRUE
J 0
(-4350 2600);
DISPLAY 0.872340 (-4350 2600);
PAINT GREEN (-4350 2600);
DISPLAY INVISIBLE (-4350 2600);
FORCEPROP 1 LAST OFFPAGE TRUE
J 0
(-4150 2575);
DISPLAY 0.872340 (-4150 2575);
PAINT GREEN (-4150 2575);
DISPLAY INVISIBLE (-4150 2575);
FORCEPROP 2 LAST CDS_LIB mstr_standard
J 0
(-4475 2700);
PAINT ORANGE (-4475 2700);
DISPLAY INVISIBLE (-4475 2700);
FORCEADD OFFPAGE..6
(-4475 2650);
FORCEPROP 2 LAST $XR2 183 
J 0
(-4995 2650);
DISPLAY 0.638298 (-4995 2650);
PAINT MONO (-4995 2650);
FORCEPROP 2 LAST $XR1 138 
J 0
(-4875 2650);
DISPLAY 0.638298 (-4875 2650);
PAINT MONO (-4875 2650);
FORCEPROP 2 LAST $XR0 108 
J 0
(-4755 2650);
DISPLAY 0.638298 (-4755 2650);
PAINT MONO (-4755 2650);
FORCEPROP 2 LAST PATH I331
J 0
(-4425 2725);
DISPLAY 1.021277 (-4425 2725);
PAINT ORANGE (-4425 2725);
DISPLAY INVISIBLE (-4425 2725);
FORCEPROP 1 LAST COMMENT_BODY TRUE
J 0
(-4375 2575);
DISPLAY 0.872340 (-4375 2575);
PAINT GREEN (-4375 2575);
DISPLAY INVISIBLE (-4375 2575);
FORCEPROP 1 LAST OFFPAGE TRUE
J 0
(-4150 2525);
DISPLAY 0.872340 (-4150 2525);
PAINT GREEN (-4150 2525);
DISPLAY INVISIBLE (-4150 2525);
FORCEPROP 2 LAST CDS_LIB mstr_standard
J 0
(-4475 2650);
PAINT ORANGE (-4475 2650);
DISPLAY INVISIBLE (-4475 2650);
FORCEADD OFFPAGE..1
(-4475 2550);
FORCEPROP 2 LAST $XR2 183 
J 0
(-4967 2550);
DISPLAY 0.638298 (-4967 2550);
PAINT MONO (-4967 2550);
FORCEPROP 2 LAST $XR1 145 
J 0
(-4847 2550);
DISPLAY 0.638298 (-4847 2550);
PAINT MONO (-4847 2550);
FORCEPROP 2 LAST $XR0 158 
J 0
(-4727 2550);
DISPLAY 0.638298 (-4727 2550);
PAINT MONO (-4727 2550);
FORCEPROP 2 LAST PATH I332
J 0
(-4425 2625);
DISPLAY 1.021277 (-4425 2625);
PAINT ORANGE (-4425 2625);
DISPLAY INVISIBLE (-4425 2625);
FORCEPROP 1 LAST COMMENT_BODY TRUE
J 0
(-4350 2450);
DISPLAY 0.872340 (-4350 2450);
PAINT GREEN (-4350 2450);
DISPLAY INVISIBLE (-4350 2450);
FORCEPROP 1 LAST OFFPAGE TRUE
J 0
(-4150 2425);
DISPLAY 0.872340 (-4150 2425);
PAINT GREEN (-4150 2425);
DISPLAY INVISIBLE (-4150 2425);
FORCEPROP 2 LAST CDS_LIB mstr_standard
J 0
(-4475 2550);
PAINT ORANGE (-4475 2550);
DISPLAY INVISIBLE (-4475 2550);
FORCEADD OFFPAGE..5
(-4475 2500);
FORCEPROP 2 LAST $XR2 158 
J 0
(-4970 2500);
DISPLAY 0.638298 (-4970 2500);
PAINT MONO (-4970 2500);
FORCEPROP 2 LAST $XR1 183 
J 0
(-4850 2500);
DISPLAY 0.638298 (-4850 2500);
PAINT MONO (-4850 2500);
FORCEPROP 2 LAST $XR0 145 
J 0
(-4730 2500);
DISPLAY 0.638298 (-4730 2500);
PAINT MONO (-4730 2500);
FORCEPROP 2 LAST PATH I333
J 0
(-4425 2575);
DISPLAY 1.021277 (-4425 2575);
PAINT ORANGE (-4425 2575);
DISPLAY INVISIBLE (-4425 2575);
FORCEPROP 1 LAST COMMENT_BODY TRUE
J 0
(-4375 2425);
DISPLAY 0.872340 (-4375 2425);
PAINT GREEN (-4375 2425);
DISPLAY INVISIBLE (-4375 2425);
FORCEPROP 1 LAST OFFPAGE TRUE
J 0
(-4150 2375);
DISPLAY 0.872340 (-4150 2375);
PAINT GREEN (-4150 2375);
DISPLAY INVISIBLE (-4150 2375);
FORCEPROP 2 LAST CDS_LIB mstr_standard
J 0
(-4475 2500);
PAINT ORANGE (-4475 2500);
DISPLAY INVISIBLE (-4475 2500);
FORCEADD OFFPAGE..1
(-4475 2450);
FORCEPROP 2 LAST $XR2 183 
J 0
(-4967 2450);
DISPLAY 0.638298 (-4967 2450);
PAINT MONO (-4967 2450);
FORCEPROP 2 LAST $XR1 145 
J 0
(-4847 2450);
DISPLAY 0.638298 (-4847 2450);
PAINT MONO (-4847 2450);
FORCEPROP 2 LAST $XR0 158 
J 0
(-4727 2450);
DISPLAY 0.638298 (-4727 2450);
PAINT MONO (-4727 2450);
FORCEPROP 2 LAST PATH I334
J 0
(-4425 2525);
DISPLAY 1.021277 (-4425 2525);
PAINT ORANGE (-4425 2525);
DISPLAY INVISIBLE (-4425 2525);
FORCEPROP 1 LAST COMMENT_BODY TRUE
J 0
(-4350 2350);
DISPLAY 0.872340 (-4350 2350);
PAINT GREEN (-4350 2350);
DISPLAY INVISIBLE (-4350 2350);
FORCEPROP 1 LAST OFFPAGE TRUE
J 0
(-4150 2325);
DISPLAY 0.872340 (-4150 2325);
PAINT GREEN (-4150 2325);
DISPLAY INVISIBLE (-4150 2325);
FORCEPROP 2 LAST CDS_LIB mstr_standard
J 0
(-4475 2450);
PAINT ORANGE (-4475 2450);
DISPLAY INVISIBLE (-4475 2450);
FORCEADD OFFPAGE..5
(-4475 2400);
FORCEPROP 2 LAST $XR2 183 
J 0
(-4970 2400);
DISPLAY 0.638298 (-4970 2400);
PAINT MONO (-4970 2400);
FORCEPROP 2 LAST $XR1 151 
J 0
(-4850 2400);
DISPLAY 0.638298 (-4850 2400);
PAINT MONO (-4850 2400);
FORCEPROP 2 LAST $XR0 145 
J 0
(-4730 2400);
DISPLAY 0.638298 (-4730 2400);
PAINT MONO (-4730 2400);
FORCEPROP 2 LAST $XR3 158 
J 0
(-4970 2400);
DISPLAY 0.638298 (-4970 2400);
PAINT MONO (-4970 2400);
FORCEPROP 2 LAST PATH I335
J 0
(-4425 2475);
DISPLAY 1.021277 (-4425 2475);
PAINT ORANGE (-4425 2475);
DISPLAY INVISIBLE (-4425 2475);
FORCEPROP 1 LAST COMMENT_BODY TRUE
J 0
(-4375 2325);
DISPLAY 0.872340 (-4375 2325);
PAINT GREEN (-4375 2325);
DISPLAY INVISIBLE (-4375 2325);
FORCEPROP 1 LAST OFFPAGE TRUE
J 0
(-4150 2275);
DISPLAY 0.872340 (-4150 2275);
PAINT GREEN (-4150 2275);
DISPLAY INVISIBLE (-4150 2275);
FORCEPROP 2 LAST CDS_LIB mstr_standard
J 0
(-4475 2400);
PAINT ORANGE (-4475 2400);
DISPLAY INVISIBLE (-4475 2400);
FORCEADD OFFPAGE..2
R 2
(-4475 1400);
FORCEPROP 2 LAST $XR1 119 
J 0
(-4850 1400);
DISPLAY 0.638298 (-4850 1400);
PAINT MONO (-4850 1400);
FORCEPROP 2 LAST $XR0 183 
J 0
(-4730 1400);
DISPLAY 0.638298 (-4730 1400);
PAINT MONO (-4730 1400);
FORCEPROP 2 LAST PATH I336
J 0
(-4425 1475);
DISPLAY 1.021277 (-4425 1475);
PAINT ORANGE (-4425 1475);
DISPLAY INVISIBLE (-4425 1475);
FORCEPROP 1 LAST COMMENT_BODY TRUE
J 2
(-4430 1305);
DISPLAY 1.170213 (-4430 1305);
PAINT GREEN (-4430 1305);
DISPLAY INVISIBLE (-4430 1305);
FORCEPROP 1 LAST OFFPAGE TRUE
J 2
(-4800 1275);
DISPLAY 1.170213 (-4800 1275);
PAINT GREEN (-4800 1275);
DISPLAY INVISIBLE (-4800 1275);
FORCEPROP 2 LAST CDS_LIB mstr_standard
J 0
(-4475 1400);
PAINT ORANGE (-4475 1400);
DISPLAY INVISIBLE (-4475 1400);
FORCEADD OFFPAGE..3
(-500 5200);
FORCEPROP 2 LAST $XR2 118 
J 0
(-46 5200);
DISPLAY 0.638298 (-46 5200);
PAINT MONO (-46 5200);
FORCEPROP 2 LAST $XR1 111 
J 0
(-166 5200);
DISPLAY 0.638298 (-166 5200);
PAINT MONO (-166 5200);
FORCEPROP 2 LAST $XR0 192 
J 0
(-286 5200);
DISPLAY 0.638298 (-286 5200);
PAINT MONO (-286 5200);
FORCEPROP 2 LASTPIN (-550 5200) SIG_NAME RST_RSMRST_N
J 2
(-560 5210);
DISPLAY 0.617021 (-560 5210);
PAINT ORANGE (-560 5210);
FORCEPROP 2 LAST PATH I337
J 0
(-325 5275);
DISPLAY 1.021277 (-325 5275);
PAINT ORANGE (-325 5275);
DISPLAY INVISIBLE (-325 5275);
FORCEPROP 1 LAST COMMENT_BODY TRUE
J 0
(-550 5100);
DISPLAY 0.872340 (-550 5100);
PAINT GREEN (-550 5100);
DISPLAY INVISIBLE (-550 5100);
FORCEPROP 1 LAST OFFPAGE TRUE
J 0
(-175 5075);
DISPLAY 0.872340 (-175 5075);
PAINT GREEN (-175 5075);
DISPLAY INVISIBLE (-175 5075);
FORCEPROP 2 LAST CDS_LIB mstr_standard
J 0
(-500 5200);
PAINT ORANGE (-500 5200);
DISPLAY INVISIBLE (-500 5200);
FORCEPROP 2 LAST ROOM PLD
J 0
(-750 5250);
DISPLAY 1.617021 (-750 5250);
PAINT WHITE (-750 5250);
DISPLAY INVISIBLE (-750 5250);
FORCEPROP 2 LAST BOM_COST SB_RESET
J 0
(-750 5250);
DISPLAY 1.617021 (-750 5250);
PAINT WHITE (-750 5250);
DISPLAY INVISIBLE (-750 5250);
FORCEADD RES..1
(-1350 5200);
FORCEPROP 1 LAST WATTAGE 1/16W
J 2
(-1375 5050);
DISPLAY 0.617021 (-1375 5050);
PAINT SKYBLUE (-1375 5050);
FORCEPROP 1 LAST MATERIAL CHIP
J 0
(-1350 5050);
DISPLAY 0.617021 (-1350 5050);
PAINT SKYBLUE (-1350 5050);
FORCEPROP 1 LAST PACK_TYPE 0402
J 0
(-1275 5100);
DISPLAY 0.617021 (-1275 5100);
PAINT SKYBLUE (-1275 5100);
FORCEPROP 1 LAST TOLERANCE 1%
J 0
(-1400 5100);
DISPLAY 0.617021 (-1400 5100);
PAINT SKYBLUE (-1400 5100);
FORCEPROP 1 LAST VALUE 33.2
J 2
(-1450 5100);
DISPLAY 0.617021 (-1450 5100);
PAINT SKYBLUE (-1450 5100);
FORCEPROP 1 LAST PART_NUMBER G21796-074
J 0
(-1500 5150);
DISPLAY 0.617021 (-1500 5150);
PAINT BLUE (-1500 5150);
FORCEPROP 1 LAST LOCATION R2R2
J 0
(-1575 5225);
DISPLAY 0.617021 (-1575 5225);
PAINT AQUA (-1575 5225);
FORCEPROP 2 LAST CDS_LIB mstr_discrete
J 0
(-1350 5200);
PAINT ORANGE (-1350 5200);
DISPLAY INVISIBLE (-1350 5200);
FORCEPROP 0 LAST BOM_COST CPLD
J 0
(-1575 5325);
DISPLAY 1.021277 (-1575 5325);
PAINT ORANGE (-1575 5325);
DISPLAY INVISIBLE (-1575 5325);
FORCEPROP 2 LAST CDS_SEC 1
J 0
(-1400 5400);
PAINT MONO (-1400 5400);
DISPLAY INVISIBLE (-1400 5400);
FORCEPROP 2 LAST $SEC 1
J 0
(-1400 5400);
PAINT MONO (-1400 5400);
DISPLAY INVISIBLE (-1400 5400);
FORCEPROP 2 LAST CDS_LOCATION R2R2
J 0
(-1575 5225);
DISPLAY 0.617021 (-1575 5225);
PAINT AQUA (-1575 5225);
DISPLAY INVISIBLE (-1575 5225);
FORCEPROP 1 LAST PATH I338
J 0
(-1400 5350);
DISPLAY 0.978723 (-1400 5350);
PAINT WHITE (-1400 5350);
DISPLAY INVISIBLE (-1400 5350);
FORCEPROP 2 LAST ROOM CPLD
J 0
(-1400 5300);
DISPLAY 1.361702 (-1400 5300);
PAINT ORANGE (-1400 5300);
DISPLAY INVISIBLE (-1400 5300);
FORCEPROP 1 LASTPIN (-1250 5200) $PN 2
J 0
(-1288 5212);
DISPLAY 0.787234 (-1288 5212);
PAINT ORANGE (-1288 5212);
DISPLAY INVISIBLE (-1288 5212);
FORCEPROP 1 LASTPIN (-1450 5200) $PN 1
J 0
(-1438 5212);
DISPLAY 0.787234 (-1438 5212);
PAINT ORANGE (-1438 5212);
DISPLAY INVISIBLE (-1438 5212);
FORCEADD OFFPAGE..6
(-2250 5200);
FORCEPROP 2 LAST $XR0 190 
J 0
(-2530 5200);
DISPLAY 0.638298 (-2530 5200);
PAINT MONO (-2530 5200);
FORCEPROP 2 LASTPIN (-2200 5200) SIG_NAME RST_RSMRST_R_N
J 0
(-2210 5210);
DISPLAY 0.617021 (-2210 5210);
PAINT ORANGE (-2210 5210);
FORCEPROP 2 LAST PATH I339
J 0
(-2200 5275);
DISPLAY 1.021277 (-2200 5275);
PAINT ORANGE (-2200 5275);
DISPLAY INVISIBLE (-2200 5275);
FORCEPROP 1 LAST COMMENT_BODY TRUE
J 0
(-2150 5125);
DISPLAY 0.872340 (-2150 5125);
PAINT GREEN (-2150 5125);
DISPLAY INVISIBLE (-2150 5125);
FORCEPROP 1 LAST OFFPAGE TRUE
J 0
(-1925 5075);
DISPLAY 0.872340 (-1925 5075);
PAINT GREEN (-1925 5075);
DISPLAY INVISIBLE (-1925 5075);
FORCEPROP 2 LAST CDS_LIB mstr_standard
J 0
(-2250 5200);
PAINT ORANGE (-2250 5200);
DISPLAY INVISIBLE (-2250 5200);
FORCEPROP 2 LAST ROOM PLD
J 0
(-2500 5250);
DISPLAY 1.617021 (-2500 5250);
PAINT WHITE (-2500 5250);
DISPLAY INVISIBLE (-2500 5250);
FORCEPROP 2 LAST BOM_COST SB_RESET
J 0
(-2500 5250);
DISPLAY 1.617021 (-2500 5250);
PAINT WHITE (-2500 5250);
DISPLAY INVISIBLE (-2500 5250);
FORCEADD OFFPAGE..2
(550 1750);
FORCEPROP 2 LAST $XR0 104 
J 0
(739 1750);
DISPLAY 0.638298 (739 1750);
PAINT MONO (739 1750);
FORCEPROP 2 LAST PATH I340
J 0
(725 1825);
DISPLAY 1.021277 (725 1825);
PAINT ORANGE (725 1825);
DISPLAY INVISIBLE (725 1825);
FORCEPROP 1 LAST COMMENT_BODY TRUE
J 0
(505 1655);
DISPLAY 1.170213 (505 1655);
PAINT GREEN (505 1655);
DISPLAY INVISIBLE (505 1655);
FORCEPROP 1 LAST OFFPAGE TRUE
J 0
(875 1625);
DISPLAY 1.170213 (875 1625);
PAINT GREEN (875 1625);
DISPLAY INVISIBLE (875 1625);
FORCEPROP 2 LAST CDS_LIB mstr_standard
J 0
(550 1750);
PAINT ORANGE (550 1750);
DISPLAY INVISIBLE (550 1750);
FORCEADD OFFPAGE..4
R 2
(-4475 1650);
FORCEPROP 2 LAST $XR0 119 
J 0
(-4727 1650);
DISPLAY 0.638298 (-4727 1650);
PAINT MONO (-4727 1650);
FORCEPROP 2 LAST PATH I341
J 0
(-4425 1725);
DISPLAY 1.021277 (-4425 1725);
PAINT ORANGE (-4425 1725);
DISPLAY INVISIBLE (-4425 1725);
FORCEPROP 1 LAST COMMENT_BODY TRUE
J 2
(-4450 1550);
DISPLAY 1.170213 (-4450 1550);
PAINT GREEN (-4450 1550);
DISPLAY INVISIBLE (-4450 1550);
FORCEPROP 1 LAST OFFPAGE TRUE
J 2
(-4800 1525);
DISPLAY 1.170213 (-4800 1525);
PAINT GREEN (-4800 1525);
DISPLAY INVISIBLE (-4800 1525);
FORCEPROP 2 LAST CDS_LIB mstr_standard
J 0
(-4475 1650);
PAINT ORANGE (-4475 1650);
DISPLAY INVISIBLE (-4475 1650);
FORCEADD OFFPAGE..4
(550 4600);
FORCEPROP 2 LAST $XR1 133 
J 0
(856 4600);
DISPLAY 0.638298 (856 4600);
PAINT MONO (856 4600);
FORCEPROP 2 LAST $XR0 119 
J 0
(736 4600);
DISPLAY 0.638298 (736 4600);
PAINT MONO (736 4600);
FORCEPROP 2 LAST PATH I342
J 0
(725 4675);
DISPLAY 1.021277 (725 4675);
PAINT ORANGE (725 4675);
DISPLAY INVISIBLE (725 4675);
FORCEPROP 1 LAST COMMENT_BODY TRUE
J 0
(525 4500);
DISPLAY 1.170213 (525 4500);
PAINT GREEN (525 4500);
DISPLAY INVISIBLE (525 4500);
FORCEPROP 1 LAST OFFPAGE TRUE
J 0
(875 4475);
DISPLAY 1.170213 (875 4475);
PAINT GREEN (875 4475);
DISPLAY INVISIBLE (875 4475);
FORCEPROP 2 LAST CDS_LIB mstr_standard
J 0
(550 4600);
PAINT ORANGE (550 4600);
DISPLAY INVISIBLE (550 4600);
FORCEADD OFFPAGE..4
(550 4450);
FORCEPROP 2 LAST $XR1 133 
J 0
(856 4450);
DISPLAY 0.638298 (856 4450);
PAINT MONO (856 4450);
FORCEPROP 2 LAST $XR0 120 
J 0
(736 4450);
DISPLAY 0.638298 (736 4450);
PAINT MONO (736 4450);
FORCEPROP 2 LAST PATH I343
J 0
(725 4525);
DISPLAY 1.021277 (725 4525);
PAINT ORANGE (725 4525);
DISPLAY INVISIBLE (725 4525);
FORCEPROP 1 LAST COMMENT_BODY TRUE
J 0
(525 4350);
DISPLAY 1.170213 (525 4350);
PAINT GREEN (525 4350);
DISPLAY INVISIBLE (525 4350);
FORCEPROP 1 LAST OFFPAGE TRUE
J 0
(875 4325);
DISPLAY 1.170213 (875 4325);
PAINT GREEN (875 4325);
DISPLAY INVISIBLE (875 4325);
FORCEPROP 2 LAST CDS_LIB mstr_standard
J 0
(550 4450);
PAINT ORANGE (550 4450);
DISPLAY INVISIBLE (550 4450);
FORCEADD OFFPAGE..4
(550 4050);
FORCEPROP 2 LAST $XR0 135 
J 0
(736 4050);
DISPLAY 0.638298 (736 4050);
PAINT MONO (736 4050);
FORCEPROP 2 LAST PATH I344
J 0
(725 4125);
DISPLAY 1.021277 (725 4125);
PAINT ORANGE (725 4125);
DISPLAY INVISIBLE (725 4125);
FORCEPROP 1 LAST COMMENT_BODY TRUE
J 0
(525 3950);
DISPLAY 1.170213 (525 3950);
PAINT GREEN (525 3950);
DISPLAY INVISIBLE (525 3950);
FORCEPROP 1 LAST OFFPAGE TRUE
J 0
(875 3925);
DISPLAY 1.170213 (875 3925);
PAINT GREEN (875 3925);
DISPLAY INVISIBLE (875 3925);
FORCEPROP 2 LAST CDS_LIB mstr_standard
J 0
(550 4050);
PAINT ORANGE (550 4050);
DISPLAY INVISIBLE (550 4050);
FORCEADD OFFPAGE..1
(-4475 4150);
FORCEPROP 2 LAST $XR0 192 
J 0
(-4727 4150);
DISPLAY 0.638298 (-4727 4150);
PAINT MONO (-4727 4150);
FORCEPROP 2 LASTPIN (-4425 4150) SIG_NAME FM_MEM_EVENT_FUNC
J 0
(-4385 4160);
DISPLAY 0.617021 (-4385 4160);
PAINT ORANGE (-4385 4160);
FORCEPROP 2 LAST PATH I345
J 0
(-4425 4225);
DISPLAY 1.021277 (-4425 4225);
PAINT ORANGE (-4425 4225);
DISPLAY INVISIBLE (-4425 4225);
FORCEPROP 1 LAST COMMENT_BODY TRUE
J 0
(-4350 4050);
DISPLAY 0.872340 (-4350 4050);
PAINT GREEN (-4350 4050);
DISPLAY INVISIBLE (-4350 4050);
FORCEPROP 1 LAST OFFPAGE TRUE
J 0
(-4150 4025);
DISPLAY 0.872340 (-4150 4025);
PAINT GREEN (-4150 4025);
DISPLAY INVISIBLE (-4150 4025);
FORCEPROP 2 LAST CDS_LIB mstr_standard
J 0
(-4475 4150);
PAINT ORANGE (-4475 4150);
DISPLAY INVISIBLE (-4475 4150);
FORCEADD OFFPAGE..5
(-4475 2000);
FORCEPROP 2 LAST $XR0 126 
J 0
(-4730 2000);
DISPLAY 0.638298 (-4730 2000);
PAINT MONO (-4730 2000);
FORCEPROP 2 LAST CDS_LIB mstr_standard
J 0
(-4475 2000);
PAINT ORANGE (-4475 2000);
DISPLAY INVISIBLE (-4475 2000);
FORCEPROP 2 LAST PATH I346
J 0
(-4425 2075);
DISPLAY 1.021277 (-4425 2075);
PAINT ORANGE (-4425 2075);
DISPLAY INVISIBLE (-4425 2075);
FORCEPROP 1 LAST OFFPAGE TRUE
J 0
(-4150 1875);
DISPLAY 0.872340 (-4150 1875);
PAINT GREEN (-4150 1875);
DISPLAY INVISIBLE (-4150 1875);
FORCEPROP 1 LAST COMMENT_BODY TRUE
J 0
(-4375 1925);
DISPLAY 0.872340 (-4375 1925);
PAINT GREEN (-4375 1925);
DISPLAY INVISIBLE (-4375 1925);
FORCEADD INTEL_CORP_BPAGE..1
(2650 500);
FORCEPROP 1 LAST CUSTOM_TXT_CDS <CURRENT_DESIGN_SHEET> OF <TOTAL_DESIGN_SHEETS>
J 0
(2150 525);
PAINT GREEN (2150 525);
FORCEPROP 1 LAST CUSTOM_TXT_CDS <CON_LAST_MODIFIED>
J 0
(725 850);
PAINT GREEN (725 850);
FORCEPROP 2 LAST CUSTOM_TXT_CDS <XR_PAGE_TITLE>
J 0
(-5240 5750);
DISPLAY 0.638298 (-5240 5750);
PAINT PINK (-5240 5750);
DISPLAY INVISIBLE (-5240 5750);
FORCEPROP 1 LAST SCH_TITLE CPLD (1 OF 3)
J 0
(-5300 550);
DISPLAY 1.212766 (-5300 550);
PAINT ORANGE (-5300 550);
FORCEPROP 1 LAST SCH_ADDRESS1 2200 Mission College Blvd.
J 0
(-1325 625);
DISPLAY 0.617021 (-1325 625);
PAINT GREEN (-1325 625);
FORCEPROP 1 LAST SCH_ADDRESS2 P.O. BOX 58119
J 0
(-1325 575);
DISPLAY 0.617021 (-1325 575);
PAINT GREEN (-1325 575);
FORCEPROP 1 LAST SCH_ADDRESS3 Santa Clara, CA 95052-8119
J 0
(-1325 525);
DISPLAY 0.617021 (-1325 525);
PAINT GREEN (-1325 525);
FORCEPROP 1 LAST SCH_NUMBER H4694802
J 0
(1350 650);
DISPLAY 1.212766 (1350 650);
PAINT YELLOW (1350 650);
FORCEPROP 1 LAST SCH_DEPT BESD
J 1
(-1800 600);
DISPLAY 1.212766 (-1800 600);
PAINT YELLOW (-1800 600);
FORCEPROP 1 LAST SCH_REV 2.420
J 0
(2400 650);
DISPLAY 1.212766 (2400 650);
PAINT YELLOW (2400 650);
FORCEPROP 2 LAST PAGE_BORDER TRUE
J 0
(-5240 5750);
DISPLAY 0.851064 (-5240 5750);
PAINT PINK (-5240 5750);
DISPLAY INVISIBLE (-5240 5750);
FORCEPROP 2 LAST CDS_LIB mstr_symbols
J 0
(2650 500);
PAINT MONO (2650 500);
DISPLAY INVISIBLE (2650 500);
FORCEPROP 1 LAST COMMENT_BODY TRUE
J 0
(2662 512);
DISPLAY 0.468085 (2662 512);
PAINT GREEN (2662 512);
DISPLAY INVISIBLE (2662 512);
FORCEPROP 1 LAST CDS_CON_LAST_MODIFIED Tue Dec 01 11:48:58 2015
J 0
(1225 825);
PAINT ORANGE (1225 825);
DISPLAY INVISIBLE (1225 825);
FORCEPROP 2 LAST CDS_XR_PAGE_TITLE CR-190 : @BASEBOARD_FAB2_LIB.BASEBOARD_FAB2(SCH_1):PAGE190
J 0
(-5240 5750);
DISPLAY 0.638298 (-5240 5750);
PAINT PINK (-5240 5750);
DISPLAY INVISIBLE (-5240 5750);
WIRE 16 -1 (-4050 5200)(-3225 5200);
FORCEPROP 0 LAST SIG_NAME RST_CPU0_LVC3_N
J 0
(-3910 5210);
DISPLAY 0.617021 (-3910 5210);
PAINT ORANGE (-3910 5210);
WIRE 16 -1 (-3225 5000)(-4050 5000);
FORCEPROP 0 LAST SIG_NAME RST_CPU1_LVC3_N
J 0
(-3910 5010);
DISPLAY 0.617021 (-3910 5010);
PAINT ORANGE (-3910 5010);
WIRE 16 -1 (-2550 3250)(-4425 3250);
FORCEPROP 0 LAST SIG_NAME FM_PVCCMCP_CPU0_EN
J 0
(-4359 3256);
DISPLAY 0.617021 (-4359 3256);
PAINT ORANGE (-4359 3256);
WIRE 16 -1 (-4875 5000)(-4250 5000);
FORCEPROP 0 LAST SIG_NAME RST_CPU1_LVC3_R1_N
J 0
(-4860 5010);
DISPLAY 0.617021 (-4860 5010);
PAINT ORANGE (-4860 5010);
WIRE 16 -1 (-4250 5200)(-4875 5200);
FORCEPROP 0 LAST SIG_NAME RST_CPU0_LVC3_R1_N
J 0
(-4860 5210);
DISPLAY 0.617021 (-4860 5210);
PAINT ORANGE (-4860 5210);
WIRE 16 -1 (-2550 4400)(-4425 4400);
FORCEPROP 0 LAST SIG_NAME FM_PCH_PLD_DATA
J 0
(-4385 4410);
DISPLAY 0.617021 (-4385 4410);
PAINT ORANGE (-4385 4410);
WIRE 16 -1 (-2550 1500)(-4425 1500);
FORCEPROP 0 LAST SIG_NAME RST_CD_CPU0_POR_N
J 0
(-4375 1510);
DISPLAY 0.617021 (-4375 1510);
PAINT ORANGE (-4375 1510);
WIRE 16 -1 (-2550 1750)(-4425 1750);
FORCEPROP 0 LAST SIG_NAME PWRGD_PVCCIN_CPU1
J 0
(-4375 1760);
DISPLAY 0.617021 (-4375 1760);
PAINT ORANGE (-4375 1760);
WIRE 16 -1 (-2550 1800)(-4425 1800);
FORCEPROP 0 LAST SIG_NAME RST_PCIE_RISER1_PERST_N
J 0
(-4375 1810);
DISPLAY 0.617021 (-4375 1810);
PAINT ORANGE (-4375 1810);
WIRE 16 -1 (-2550 2150)(-4425 2150);
FORCEPROP 0 LAST SIG_NAME PWRGD_CPU0_LVC3
J 0
(-4375 2160);
DISPLAY 0.617021 (-4375 2160);
PAINT ORANGE (-4375 2160);
WIRE 16 -1 (-2550 2300)(-4425 2300);
FORCEPROP 0 LAST SIG_NAME PWRGD_PVSA_CPU0
J 0
(-4375 2310);
DISPLAY 0.617021 (-4375 2310);
PAINT ORANGE (-4375 2310);
WIRE 16 -1 (-2550 2800)(-4425 2800);
FORCEPROP 0 LAST SIG_NAME SGPIO_BMC_DOUT
J 0
(-4375 2810);
DISPLAY 0.617021 (-4375 2810);
PAINT ORANGE (-4375 2810);
WIRE 16 -1 (-2550 2750)(-4425 2750);
FORCEPROP 0 LAST SIG_NAME FM_PVCCIOMCP_CPU0_EN
J 0
(-4374 2766);
DISPLAY 0.617021 (-4374 2766);
PAINT ORANGE (-4374 2766);
WIRE 16 -1 (-2550 2950)(-4425 2950);
FORCEPROP 0 LAST SIG_NAME SGPIO_BMC_CLK
J 0
(-4375 2960);
DISPLAY 0.617021 (-4375 2960);
PAINT ORANGE (-4375 2960);
WIRE 16 -1 (-2550 3300)(-4425 3300);
FORCEPROP 0 LAST SIG_NAME FM_SLPS3_N
J 0
(-4375 3310);
DISPLAY 0.617021 (-4375 3310);
PAINT ORANGE (-4375 3310);
WIRE 16 -1 (-2550 3400)(-4425 3400);
FORCEPROP 0 LAST SIG_NAME PWRGD_P3V3
J 0
(-4375 3410);
DISPLAY 0.617021 (-4375 3410);
PAINT ORANGE (-4375 3410);
WIRE 16 -1 (-2550 3450)(-4425 3450);
FORCEPROP 0 LAST SIG_NAME FM_CPU0_FIVR_FAULT_LVT3_N
J 0
(-4375 3460);
DISPLAY 0.617021 (-4375 3460);
PAINT ORANGE (-4375 3460);
WIRE 16 -1 (-2550 3500)(-4425 3500);
FORCEPROP 0 LAST SIG_NAME FM_CPU0_PKGID1
J 0
(-4375 3510);
DISPLAY 0.617021 (-4375 3510);
PAINT ORANGE (-4375 3510);
WIRE 16 -1 (-2550 3550)(-4425 3550);
FORCEPROP 0 LAST SIG_NAME FM_CPU0_PKGID2
J 0
(-4375 3560);
DISPLAY 0.617021 (-4375 3560);
PAINT ORANGE (-4375 3560);
WIRE 16 -1 (-2550 3700)(-4425 3700);
FORCEPROP 0 LAST SIG_NAME FM_DEBUG_RST_BTN_N
J 0
(-4375 3710);
DISPLAY 0.617021 (-4375 3710);
PAINT ORANGE (-4375 3710);
WIRE 16 -1 (-2550 3750)(-4425 3750);
FORCEPROP 0 LAST SIG_NAME FM_CPU0_PROC_ID0
J 0
(-4375 3760);
DISPLAY 0.617021 (-4375 3760);
PAINT ORANGE (-4375 3760);
WIRE 16 -1 (-2550 3800)(-4425 3800);
FORCEPROP 0 LAST SIG_NAME FM_CPU0_PROC_ID1
J 0
(-4375 3810);
DISPLAY 0.617021 (-4375 3810);
PAINT ORANGE (-4375 3810);
WIRE 16 -1 (-2550 3900)(-4425 3900);
FORCEPROP 0 LAST SIG_NAME FM_PWR_BTN_N
J 0
(-4375 3910);
DISPLAY 0.617021 (-4375 3910);
PAINT ORANGE (-4375 3910);
WIRE 16 -1 (-2550 4050)(-4425 4050);
FORCEPROP 0 LAST SIG_NAME CLK_32K_SUSCLK_PLD
J 0
(-4375 4060);
DISPLAY 0.617021 (-4375 4060);
PAINT ORANGE (-4375 4060);
WIRE 16 -1 (-2550 4000)(-4425 4000);
FORCEPROP 0 LAST SIG_NAME FM_CPU0_PKGID0
J 0
(-4375 4010);
DISPLAY 0.617021 (-4375 4010);
PAINT ORANGE (-4375 4010);
WIRE 16 -1 (-2550 4300)(-4425 4300);
FORCEPROP 0 LAST SIG_NAME FM_CPU_CATERR_DLY_LVT3_N
J 0
(-4375 4310);
DISPLAY 0.617021 (-4375 4310);
PAINT ORANGE (-4375 4310);
WIRE 16 -1 (-2550 4450)(-4425 4450);
FORCEPROP 0 LAST SIG_NAME RST_PCIE_PCH_PERST_N
J 0
(-4375 4460);
DISPLAY 0.617021 (-4375 4460);
PAINT ORANGE (-4375 4460);
WIRE 16 -1 (-2550 3950)(-4425 3950);
FORCEPROP 0 LAST SIG_NAME PU_RST_PERST_BIT0
J 0
(-4375 3960);
DISPLAY 0.617021 (-4375 3960);
PAINT ORANGE (-4375 3960);
WIRE 16 -1 (-2550 3150)(-4425 3150);
FORCEPROP 0 LAST SIG_NAME PWRGD_P5V
J 0
(-4375 3160);
DISPLAY 0.617021 (-4375 3160);
PAINT ORANGE (-4375 3160);
WIRE 16 -1 (-2550 4200)(-4425 4200);
FORCEPROP 0 LAST SIG_NAME RST_PCIE_CPU_DEV1_N
J 0
(-4375 4210);
DISPLAY 0.617021 (-4375 4210);
PAINT ORANGE (-4375 4210);
WIRE 16 -1 (-2550 3050)(-4425 3050);
FORCEPROP 0 LAST SIG_NAME RST_PCIE_CPU_DEV2_N
J 0
(-4375 3060);
DISPLAY 0.617021 (-4375 3060);
PAINT ORANGE (-4375 3060);
WIRE 16 -1 (-2550 3000)(-4425 3000);
FORCEPROP 0 LAST SIG_NAME RST_PCIE_CPU_DEV3_N
J 0
(-4375 3010);
DISPLAY 0.617021 (-4375 3010);
PAINT ORANGE (-4375 3010);
WIRE 16 -1 (-2550 1450)(-4425 1450);
FORCEPROP 0 LAST SIG_NAME FM_BMC_CPLD_GPO
J 0
(-4375 1460);
DISPLAY 0.617021 (-4375 1460);
PAINT ORANGE (-4375 1460);
WIRE 16 -1 (-2550 3200)(-4425 3200);
FORCEPROP 0 LAST SIG_NAME FM_MP_PS_FAIL_N
J 0
(-4375 3210);
DISPLAY 0.617021 (-4375 3210);
PAINT ORANGE (-4375 3210);
WIRE 16 -1 (-2550 1550)(-4425 1550);
FORCEPROP 0 LAST SIG_NAME PWRGD_PVPP_GHJ
J 0
(-4375 1560);
DISPLAY 0.617021 (-4375 1560);
PAINT ORANGE (-4375 1560);
WIRE 16 -1 (-2550 1700)(-4425 1700);
FORCEPROP 0 LAST SIG_NAME PWRGD_PVPP_KLM
J 0
(-4375 1710);
DISPLAY 0.617021 (-4375 1710);
PAINT ORANGE (-4375 1710);
WIRE 16 -1 (-2550 2050)(-4425 2050);
FORCEPROP 0 LAST SIG_NAME CLK_25M_CPLD
J 0
(-4375 2060);
DISPLAY 0.617021 (-4375 2060);
PAINT ORANGE (-4375 2060);
WIRE 16 -1 (-2550 1950)(-4425 1950);
FORCEPROP 0 LAST SIG_NAME PWRGD_PVCCIN_CPU0
J 0
(-4375 1960);
DISPLAY 0.617021 (-4375 1960);
PAINT ORANGE (-4375 1960);
WIRE 16 -1 (-2550 1900)(-4425 1900);
FORCEPROP 0 LAST SIG_NAME PWRGD_PVCCMCP_CPU1
J 0
(-4375 1904);
DISPLAY 0.617021 (-4375 1904);
PAINT ORANGE (-4375 1904);
WIRE 16 -1 (-2550 2200)(-4425 2200);
FORCEPROP 0 LAST SIG_NAME SGPIO_BMC_LD_N
J 0
(-4370 2210);
DISPLAY 0.617021 (-4370 2210);
PAINT ORANGE (-4370 2210);
WIRE 16 -1 (-2550 2700)(-4425 2700);
FORCEPROP 0 LAST SIG_NAME SMB_SLOTX24_PCH_STBY_LVC3_SCL
J 0
(-4375 2710);
DISPLAY 0.617021 (-4375 2710);
PAINT ORANGE (-4375 2710);
WIRE 16 -1 (-2550 2650)(-4425 2650);
FORCEPROP 0 LAST SIG_NAME SMB_SLOTX24_PCH_STBY_LVC3_SDA
J 0
(-4370 2660);
DISPLAY 0.617021 (-4370 2660);
PAINT ORANGE (-4370 2660);
WIRE 16 -1 (-2550 2550)(-4425 2550);
FORCEPROP 0 LAST SIG_NAME SP1_BMC_HOST_UART_RX
J 0
(-4375 2560);
DISPLAY 0.617021 (-4375 2560);
PAINT ORANGE (-4375 2560);
WIRE 16 -1 (-2550 2500)(-4425 2500);
FORCEPROP 0 LAST SIG_NAME SP1_BMC_HOST_UART_TX
J 0
(-4375 2510);
DISPLAY 0.617021 (-4375 2510);
PAINT ORANGE (-4375 2510);
WIRE 16 -1 (-2550 2450)(-4425 2450);
FORCEPROP 0 LAST SIG_NAME UART_BMC_RXD5
J 0
(-4370 2460);
DISPLAY 0.617021 (-4370 2460);
PAINT ORANGE (-4370 2460);
WIRE 16 -1 (-2550 2400)(-4425 2400);
FORCEPROP 0 LAST SIG_NAME UART_BMC_TXD5
J 0
(-4370 2410);
DISPLAY 0.617021 (-4370 2410);
PAINT ORANGE (-4370 2410);
WIRE 16 -1 (-2550 1400)(-4425 1400);
FORCEPROP 0 LAST SIG_NAME FM_UART_ALERT_N
J 0
(-4375 1410);
DISPLAY 0.617021 (-4375 1410);
PAINT ORANGE (-4375 1410);
WIRE 16 -1 (-2550 1650)(-4425 1650);
FORCEPROP 0 LAST SIG_NAME FM_GLOBAL_RST_WARN_N
J 0
(-4375 1660);
DISPLAY 0.617021 (-4375 1660);
PAINT ORANGE (-4375 1660);
WIRE 16 -1 (-2550 4150)(-4425 4150);
WIRE 16 -1 (-2550 2000)(-4425 2000);
FORCEPROP 0 LAST SIG_NAME RST_RSMRST_DLY
J 0
(-4375 2010);
DISPLAY 0.617021 (-4375 2010);
PAINT ORANGE (-4375 2010);
WIRE 16 -1 (-2550 3650)(-4425 3650);
FORCEPROP 0 LAST SIG_NAME RST_RSMRST_R_N
J 0
(-4375 3660);
DISPLAY 0.617021 (-4375 3660);
PAINT ORANGE (-4375 3660);
WIRE 16 -1 (-2550 2250)(-3900 2250);
FORCEPROP 0 LAST SIG_NAME TP_CPLD1_PL11A
J 0
(-3850 2260);
DISPLAY 0.617021 (-3850 2260);
PAINT ORANGE (-3850 2260);
FORCEPROP 2 LASTPROP $XRERR UNIQUE?
J 0
(-4140 2250);
DISPLAY 0.638298 (-4140 2250);
PAINT MONO (-4140 2250);
DISPLAY INVISIBLE (-4140 2250);
WIRE 16 -1 (-2550 2900)(-3900 2900);
FORCEPROP 0 LAST SIG_NAME TP_CPLD1_PL7D_PCLKT4_0
J 0
(-3895 2910);
DISPLAY 0.617021 (-3895 2910);
PAINT ORANGE (-3895 2910);
FORCEPROP 2 LASTPROP $XRERR UNIQUE?
J 0
(-4140 2900);
DISPLAY 0.638298 (-4140 2900);
PAINT MONO (-4140 2900);
DISPLAY INVISIBLE (-4140 2900);
WIRE 16 -1 (-2550 4250)(-3900 4250);
FORCEPROP 0 LAST SIG_NAME TP_CPLD1_PL2B_L_GPLLC_IN
J 0
(-3895 4260);
DISPLAY 0.617021 (-3895 4260);
PAINT ORANGE (-3895 4260);
FORCEPROP 2 LASTPROP $XRERR UNIQUE?
J 0
(-4140 4250);
DISPLAY 0.638298 (-4140 4250);
PAINT MONO (-4140 4250);
DISPLAY INVISIBLE (-4140 4250);
WIRE 16 -1 (-2550 4500)(-3900 4500);
FORCEPROP 0 LAST SIG_NAME TP_CPLD1_PL1B_L_GPLLC_FB
J 0
(-3895 4510);
DISPLAY 0.617021 (-3895 4510);
PAINT ORANGE (-3895 4510);
FORCEPROP 2 LASTPROP $XRERR UNIQUE?
J 0
(-4140 4500);
DISPLAY 0.638298 (-4140 4500);
PAINT MONO (-4140 4500);
DISPLAY INVISIBLE (-4140 4500);
WIRE 16 -1 (-2550 4550)(-3900 4550);
FORCEPROP 0 LAST SIG_NAME TP_CPLD1_PL1A_L_GPLLT_FB
J 0
(-3895 4560);
DISPLAY 0.617021 (-3895 4560);
PAINT ORANGE (-3895 4560);
FORCEPROP 2 LASTPROP $XRERR UNIQUE?
J 0
(-4140 4550);
DISPLAY 0.638298 (-4140 4550);
PAINT MONO (-4140 4550);
DISPLAY INVISIBLE (-4140 4550);
WIRE 16 -1 (-1450 5200)(-2200 5200);
WIRE 16 -1 (-1250 5200)(-550 5200);
WIRE 16 -1 (-1350 1400)(25 1400);
FORCEPROP 2 LAST SIG_NAME TP_CPLD1_PB25B_SI_SISPI
J 0
(-1125 1410);
DISPLAY 0.617021 (-1125 1410);
PAINT ORANGE (-1125 1410);
FORCEPROP 2 LASTPROP $XRERR UNIQUE?
J 0
(55 1400);
DISPLAY 0.638298 (55 1400);
PAINT MONO (55 1400);
DISPLAY INVISIBLE (55 1400);
WIRE 16 -1 (-1350 2800)(25 2800);
FORCEPROP 2 LAST SIG_NAME TP_CPLD1_PB16B_PCLKC2_1
J 0
(-1125 2810);
DISPLAY 0.617021 (-1125 2810);
PAINT ORANGE (-1125 2810);
FORCEPROP 2 LASTPROP $XRERR UNIQUE?
J 0
(55 2800);
DISPLAY 0.638298 (55 2800);
PAINT MONO (55 2800);
DISPLAY INVISIBLE (55 2800);
WIRE 16 -1 (-1350 2850)(25 2850);
FORCEPROP 2 LAST SIG_NAME TP_CPLD1_PB16A_PCLKT2_1
J 0
(-1125 2875);
DISPLAY 0.617021 (-1125 2875);
PAINT ORANGE (-1125 2875);
FORCEPROP 2 LASTPROP $XRERR UNIQUE?
J 0
(55 2850);
DISPLAY 0.638298 (55 2850);
PAINT MONO (55 2850);
DISPLAY INVISIBLE (55 2850);
WIRE 16 -1 (-1350 3350)(25 3350);
FORCEPROP 2 LAST SIG_NAME TP_CPLD1_PB11B_PCLKC2_0
J 0
(-1125 3360);
DISPLAY 0.617021 (-1125 3360);
PAINT ORANGE (-1125 3360);
FORCEPROP 2 LASTPROP $XRERR UNIQUE?
J 0
(55 3350);
DISPLAY 0.638298 (55 3350);
PAINT MONO (55 3350);
DISPLAY INVISIBLE (55 3350);
WIRE 16 -1 (-1350 3750)(25 3750);
FORCEPROP 0 LAST SIG_NAME TP_CPLD1_PB8D
J 0
(-1125 3760);
DISPLAY 0.617021 (-1125 3760);
PAINT ORANGE (-1125 3760);
FORCEPROP 2 LASTPROP $XRERR UNIQUE?
J 0
(55 3750);
DISPLAY 0.638298 (55 3750);
PAINT MONO (55 3750);
DISPLAY INVISIBLE (55 3750);
WIRE 16 -1 (-1350 3850)(25 3850);
FORCEPROP 2 LAST SIG_NAME TP_CPLD1_PB8B_SO_SPISO
J 0
(-1125 3860);
DISPLAY 0.617021 (-1125 3860);
PAINT ORANGE (-1125 3860);
FORCEPROP 2 LASTPROP $XRERR UNIQUE?
J 0
(55 3850);
DISPLAY 0.638298 (55 3850);
PAINT MONO (55 3850);
DISPLAY INVISIBLE (55 3850);
WIRE 16 -1 (-1350 3900)(25 3900);
FORCEPROP 2 LAST SIG_NAME TP_CPLD1_PB8A_MCLK_CCLK
J 0
(-1125 3910);
DISPLAY 0.617021 (-1125 3910);
PAINT ORANGE (-1125 3910);
FORCEPROP 2 LASTPROP $XRERR UNIQUE?
J 0
(55 3900);
DISPLAY 0.638298 (55 3900);
PAINT MONO (55 3900);
DISPLAY INVISIBLE (55 3900);
WIRE 16 -1 (-1350 4350)(25 4350);
FORCEPROP 2 LAST SIG_NAME TP_CPLD1_PB5A_CSSPIN
J 0
(-1125 4360);
DISPLAY 0.617021 (-1125 4360);
PAINT ORANGE (-1125 4360);
FORCEPROP 2 LASTPROP $XRERR UNIQUE?
J 0
(55 4350);
DISPLAY 0.638298 (55 4350);
PAINT MONO (55 4350);
DISPLAY INVISIBLE (55 4350);
WIRE 16 -1 (-1350 4500)(500 4500);
FORCEPROP 0 LAST SIG_NAME FM_ADR_MODE_SEL
J 0
(-1110 4510);
DISPLAY 0.617021 (-1110 4510);
PAINT ORANGE (-1110 4510);
WIRE 16 -1 (-1350 4100)(500 4100);
FORCEPROP 2 LAST SIG_NAME RST_PCIE_M2_DEV_N
J 0
(-1125 4110);
DISPLAY 0.617021 (-1125 4110);
PAINT ORANGE (-1125 4110);
WIRE 16 -1 (-1350 3650)(500 3650);
FORCEPROP 2 LAST SIG_NAME PWRGD_PVTT_CPU1
J 0
(-1125 3660);
DISPLAY 0.617021 (-1125 3660);
PAINT ORANGE (-1125 3660);
WIRE 16 -1 (-1350 3150)(500 3150);
FORCEPROP 2 LAST SIG_NAME PWRGD_PVNN_P1V05_PCH
J 0
(-1125 3160);
DISPLAY 0.617021 (-1125 3160);
PAINT ORANGE (-1125 3160);
WIRE 16 -1 (-1350 2350)(500 2350);
FORCEPROP 2 LAST SIG_NAME RST_CD_CPU1_POR_N
J 0
(-1125 2360);
DISPLAY 0.617021 (-1125 2360);
PAINT ORANGE (-1125 2360);
WIRE 16 -1 (-1350 2250)(500 2250);
FORCEPROP 2 LAST SIG_NAME RST_CPU1_LVC3_R1_N
J 0
(-1125 2260);
DISPLAY 0.617021 (-1125 2260);
PAINT ORANGE (-1125 2260);
WIRE 16 -1 (-1350 2100)(500 2100);
FORCEPROP 2 LAST SIG_NAME FM_CPU1_PKGID2
J 0
(-1125 2110);
DISPLAY 0.617021 (-1125 2110);
PAINT ORANGE (-1125 2110);
WIRE 16 -1 (-1350 2000)(500 2000);
FORCEPROP 2 LAST SIG_NAME PWRGD_CPU1_LVC3
J 0
(-1125 2010);
DISPLAY 0.617021 (-1125 2010);
PAINT ORANGE (-1125 2010);
WIRE 16 -1 (500 1850)(-1350 1850);
FORCEPROP 2 LAST SIG_NAME FM_DB1200ZL_BCLKS_EN_N
J 0
(-1125 1860);
DISPLAY 0.617021 (-1125 1860);
PAINT ORANGE (-1125 1860);
WIRE 16 -1 (-1350 1700)(500 1700);
FORCEPROP 2 LAST SIG_NAME FM_CPU0_SKTOCC_LVT3_N
J 0
(-1125 1710);
DISPLAY 0.617021 (-1125 1710);
PAINT ORANGE (-1125 1710);
WIRE 16 -1 (-1350 1600)(500 1600);
FORCEPROP 2 LAST SIG_NAME FM_CPU1_PKGID1
J 0
(-1125 1610);
DISPLAY 0.617021 (-1125 1610);
PAINT ORANGE (-1125 1610);
WIRE 16 -1 (-1350 1300)(500 1300);
FORCEPROP 2 LAST SIG_NAME FM_CPU_CATERR_LVT3_N
J 0
(-1125 1310);
DISPLAY 0.617021 (-1125 1310);
PAINT ORANGE (-1125 1310);
WIRE 16 -1 (-1350 1350)(500 1350);
FORCEPROP 2 LAST SIG_NAME PWRGD_DRAMPWRGD
J 0
(-1125 1360);
DISPLAY 0.617021 (-1125 1360);
PAINT ORANGE (-1125 1360);
WIRE 16 -1 (-1350 1450)(500 1450);
FORCEPROP 2 LAST SIG_NAME FM_CPU1_PKGID0
J 0
(-1125 1460);
DISPLAY 0.617021 (-1125 1460);
PAINT ORANGE (-1125 1460);
WIRE 16 -1 (-1350 1800)(500 1800);
FORCEPROP 2 LAST SIG_NAME FM_CPU1_SKTOCC_LVT3_N
J 0
(-1125 1810);
DISPLAY 0.617021 (-1125 1810);
PAINT ORANGE (-1125 1810);
WIRE 16 -1 (-1350 1950)(500 1950);
FORCEPROP 2 LAST SIG_NAME XDP_SYSPWROK
J 0
(-1125 1960);
DISPLAY 0.617021 (-1125 1960);
PAINT ORANGE (-1125 1960);
WIRE 16 -1 (-1350 2200)(500 2200);
FORCEPROP 2 LAST SIG_NAME XDP_PWRGD_RST_N
J 0
(-1125 2210);
DISPLAY 0.617021 (-1125 2210);
PAINT ORANGE (-1125 2210);
WIRE 16 -1 (-1350 2300)(500 2300);
FORCEPROP 2 LAST SIG_NAME RST_CPU0_LVC3_R1_N
J 0
(-1125 2310);
DISPLAY 0.617021 (-1125 2310);
PAINT ORANGE (-1125 2310);
WIRE 16 -1 (-1350 2750)(500 2750);
FORCEPROP 2 LAST SIG_NAME FM_PVCCMCP_CPU1_EN
J 0
(-1125 2760);
DISPLAY 0.617021 (-1125 2760);
PAINT ORANGE (-1125 2760);
WIRE 16 -1 (-1350 3400)(500 3400);
FORCEPROP 2 LAST SIG_NAME FM_PVCCIO_CPU1_EN
J 0
(-1125 3410);
DISPLAY 0.617021 (-1125 3410);
PAINT ORANGE (-1125 3410);
WIRE 16 -1 (-1350 3550)(500 3550);
FORCEPROP 2 LAST SIG_NAME FM_PVCCIO_CPU0_EN
J 0
(-1125 3560);
DISPLAY 0.617021 (-1125 3560);
PAINT ORANGE (-1125 3560);
WIRE 16 -1 (-1350 3600)(500 3600);
FORCEPROP 2 LAST SIG_NAME FM_PVCCIOMCP_CPU1_EN
J 0
(-1125 3610);
DISPLAY 0.617021 (-1125 3610);
PAINT ORANGE (-1125 3610);
WIRE 16 -1 (-1350 3800)(500 3800);
FORCEPROP 2 LAST SIG_NAME PWRGD_PVCCIOMCP_CPU0
J 0
(-1125 3810);
DISPLAY 0.617021 (-1125 3810);
PAINT ORANGE (-1125 3810);
WIRE 16 -1 (-1350 4150)(500 4150);
FORCEPROP 2 LAST SIG_NAME PWRGD_PVCCIOMCP_CPU1
J 0
(-1125 4160);
DISPLAY 0.617021 (-1125 4160);
PAINT ORANGE (-1125 4160);
WIRE 16 -1 (-1350 4300)(500 4300);
FORCEPROP 2 LAST SIG_NAME PWRGD_PVCCMCP_CPU0
J 0
(-1125 4310);
DISPLAY 0.617021 (-1125 4310);
PAINT ORANGE (-1125 4310);
WIRE 16 -1 (-1350 4550)(500 4550);
FORCEPROP 2 LAST SIG_NAME PWRGD_PVSA_CPU1
J 0
(-1125 4560);
DISPLAY 0.617021 (-1125 4560);
PAINT ORANGE (-1125 4560);
WIRE 16 -1 (-1350 2050)(500 2050);
FORCEPROP 2 LAST SIG_NAME FM_UARTSW_MSB_N
J 0
(-1125 2060);
DISPLAY 0.617021 (-1125 2060);
PAINT ORANGE (-1125 2060);
WIRE 16 -1 (-1350 2600)(500 2600);
FORCEPROP 2 LAST SIG_NAME FM_UARTSW_LSB_N
J 0
(-1125 2610);
DISPLAY 0.617021 (-1125 2610);
PAINT ORANGE (-1125 2610);
WIRE 16 -1 (-1350 3000)(500 3000);
FORCEPROP 0 LAST SIG_NAME FM_IE_DISABLE_N
J 0
(-1125 3010);
DISPLAY 0.617021 (-1125 3010);
PAINT ORANGE (-1125 3010);
WIRE 16 -1 (-1350 3050)(500 3050);
FORCEPROP 2 LAST SIG_NAME FM_156M_CPU1_BRD_OSC_EN
J 0
(-1125 3060);
DISPLAY 0.617021 (-1125 3060);
PAINT ORANGE (-1125 3060);
WIRE 16 -1 (-1350 2550)(500 2550);
FORCEPROP 2 LAST SIG_NAME FM_156M_CPU0_BRD_OSC_EN
J 0
(-1125 2560);
DISPLAY 0.617021 (-1125 2560);
PAINT ORANGE (-1125 2560);
WIRE 16 -1 (-1350 2700)(500 2700);
FORCEPROP 2 LAST SIG_NAME FM_CPLD_BMC_PWRDN_N
J 0
(-1125 2710);
DISPLAY 0.617021 (-1125 2710);
PAINT ORANGE (-1125 2710);
WIRE 16 -1 (-1350 2450)(500 2450);
FORCEPROP 0 LAST SIG_NAME FM_SOL_UART_CH_SEL
J 0
(-1125 2460);
DISPLAY 0.617021 (-1125 2460);
PAINT ORANGE (-1125 2460);
WIRE 16 -1 (-1350 3100)(500 3100);
FORCEPROP 2 LAST SIG_NAME FM_CPLD_DBG_PWR_EN_N
J 0
(-1125 3110);
DISPLAY 0.617021 (-1125 3110);
PAINT ORANGE (-1125 3110);
WIRE 16 -1 (-1350 2500)(500 2500);
FORCEPROP 2 LAST SIG_NAME FM_CPLD_UART_CH_LOCK_N
J 0
(-1125 2510);
DISPLAY 0.617021 (-1125 2510);
PAINT ORANGE (-1125 2510);
WIRE 16 -1 (-1350 3250)(500 3250);
FORCEPROP 2 LAST SIG_NAME PWRGD_PVCCIO_CPU0
J 0
(-1125 3260);
DISPLAY 0.617021 (-1125 3260);
PAINT ORANGE (-1125 3260);
WIRE 16 -1 (-1350 3500)(500 3500);
FORCEPROP 2 LAST SIG_NAME PWRGD_PVPP_ABC
J 0
(-1125 3510);
DISPLAY 0.617021 (-1125 3510);
PAINT ORANGE (-1125 3510);
WIRE 16 -1 (-1350 4000)(500 4000);
FORCEPROP 2 LAST SIG_NAME FM_BMC_CPLD_MP_RST_N
J 0
(-1125 4010);
DISPLAY 0.617021 (-1125 4010);
PAINT ORANGE (-1125 4010);
WIRE 16 -1 (-1350 3300)(500 3300);
FORCEPROP 0 LAST SIG_NAME PWRGD_PVPP_DEF
J 0
(-1125 3310);
DISPLAY 0.617021 (-1125 3310);
PAINT ORANGE (-1125 3310);
WIRE 16 -1 (-1350 1550)(500 1550);
FORCEPROP 2 LAST SIG_NAME FM_CPU_MSMI_LVT3_N
J 0
(-1125 1560);
DISPLAY 0.617021 (-1125 1560);
PAINT ORANGE (-1125 1560);
WIRE 16 -1 (-1350 1750)(500 1750);
FORCEPROP 2 LAST SIG_NAME FM_CPU0_VRM_OSC_EN
J 0
(-1125 1760);
DISPLAY 0.617021 (-1125 1760);
PAINT ORANGE (-1125 1760);
WIRE 16 -1 (-1350 4600)(500 4600);
FORCEPROP 2 LAST SIG_NAME FM_CPU1_RC_EN
J 0
(-1125 4610);
DISPLAY 0.617021 (-1125 4610);
PAINT ORANGE (-1125 4610);
WIRE 16 -1 (-1350 4450)(500 4450);
FORCEPROP 2 LAST SIG_NAME FM_CPU0_RC_EN
J 0
(-1125 4460);
DISPLAY 0.617021 (-1125 4460);
PAINT ORANGE (-1125 4460);
WIRE 16 -1 (-1350 4050)(500 4050);
FORCEPROP 2 LAST SIG_NAME FM_DIS_ADR_DLY
J 0
(-1125 4060);
DISPLAY 0.617021 (-1125 4060);
PAINT ORANGE (-1125 4060);
FORCENOTE
ROOM=CPLD
(-5225 775) 0;
DISPLAY LEFT (-5225 775);
DISPLAY 1.021277 (-5225 775);
PAINT PURPLE (-5225 775);
FORCENOTE
BOM_COST=CPLD
(-5225 725) 0;
DISPLAY LEFT (-5225 725);
DISPLAY 1.021277 (-5225 725);
PAINT PURPLE (-5225 725);
QUIT
